FILE_TYPE = MACRO_DRAWING;
SET COLOR_WIRE YELLOW;
SET COLOR_PROP MONO;
SET COLOR_DOT WHITE;
SET COLOR_ARC YELLOW;
SET COLOR_BODY GREEN;
SET COLOR_NOTE MONO;
SET PROP_DISPLAY VALUE;
SET PAGE_NUMBER P167;
FORCEADD TMP421..1
(-4000 4450);
FORCEPROP 2 LASTPIN (-4300 4450) $PN 2
J 2
(-4310 4460);
DISPLAY 0.617021 (-4310 4460);
PAINT ORANGE (-4310 4460);
FORCEPROP 2 LASTPIN (-4300 4600) $PN 8
J 2
(-4310 4610);
DISPLAY 0.617021 (-4310 4610);
PAINT ORANGE (-4310 4610);
FORCEPROP 1 LAST MATERIAL IC
J 0
(-4250 4800);
DISPLAY 0.617021 (-4250 4800);
PAINT SKYBLUE (-4250 4800);
FORCEPROP 1 LAST LOCATION U9B4
J 0
(-4250 4850);
DISPLAY 0.617021 (-4250 4850);
PAINT AQUA (-4250 4850);
FORCEPROP 2 LASTPIN (-3700 4500) $PN 6
J 0
(-3690 4510);
DISPLAY 0.617021 (-3690 4510);
PAINT ORANGE (-3690 4510);
FORCEPROP 2 LASTPIN (-3700 4250) $PN 5
J 0
(-3690 4260);
DISPLAY 0.617021 (-3690 4260);
PAINT ORANGE (-3690 4260);
FORCEPROP 2 LASTPIN (-3700 4450) $PN 7
J 0
(-3690 4460);
DISPLAY 0.617021 (-3690 4460);
PAINT ORANGE (-3690 4460);
FORCEPROP 2 LASTPIN (-4300 4300) $PN 4
J 2
(-4310 4310);
DISPLAY 0.617021 (-4310 4310);
PAINT ORANGE (-4310 4310);
FORCEPROP 2 LASTPIN (-4300 4500) $PN 1
J 2
(-4310 4510);
DISPLAY 0.617021 (-4310 4510);
PAINT ORANGE (-4310 4510);
FORCEPROP 1 LAST PART_NUMBER G62962-001
J 0
(-4250 4150);
DISPLAY 0.617021 (-4250 4150);
PAINT BLUE (-4250 4150);
FORCEPROP 2 LASTPIN (-4300 4350) $PN 3
J 2
(-4310 4360);
DISPLAY 0.617021 (-4310 4360);
PAINT ORANGE (-4310 4360);
FORCEPROP 2 LAST ROOM TEMP_SENSORS
J 0
(-4250 4900);
DISPLAY 1.021277 (-4250 4900);
PAINT ORANGE (-4250 4900);
DISPLAY INVISIBLE (-4250 4900);
FORCEPROP 2 LAST CDS_LOCATION U9B4
J 0
(-4250 4850);
DISPLAY 0.617021 (-4250 4850);
PAINT AQUA (-4250 4850);
DISPLAY INVISIBLE (-4250 4850);
FORCEPROP 2 LAST SEC 1
J 0
(-4250 4900);
DISPLAY 0.680851 (-4250 4900);
PAINT MONO (-4250 4900);
DISPLAY INVISIBLE (-4250 4900);
FORCEPROP 2 LAST BOM_COST SM_THERM
J 0
(-4250 4950);
DISPLAY 1.021277 (-4250 4950);
PAINT ORANGE (-4250 4950);
DISPLAY INVISIBLE (-4250 4950);
FORCEPROP 2 LAST SEC_TYPE TSSOP
J 0
(-4250 4900);
DISPLAY 1.021277 (-4250 4900);
PAINT ORANGE (-4250 4900);
DISPLAY INVISIBLE (-4250 4900);
FORCEPROP 1 LAST PACK_TYPE TSSOP
J 0
(-4250 4900);
PAINT SKYBLUE (-4250 4900);
DISPLAY INVISIBLE (-4250 4900);
FORCEPROP 2 LAST CDS_LIB mstr_analog
J 0
(-4000 4450);
PAINT ORANGE (-4000 4450);
DISPLAY INVISIBLE (-4000 4450);
FORCEPROP 1 LAST PATH I1
J 0
(-4000 4800);
PAINT GREEN (-4000 4800);
DISPLAY INVISIBLE (-4000 4800);
FORCEADD RES..2
(-4775 4075);
FORCEPROP 1 LAST MATERIAL CHIP
J 0
(-4735 4000);
DISPLAY 0.617021 (-4735 4000);
PAINT SKYBLUE (-4735 4000);
FORCEPROP 1 LASTPIN (-4775 3975) $PN 2
J 0
(-4770 3985);
DISPLAY 0.617021 (-4770 3985);
PAINT ORANGE (-4770 3985);
FORCEPROP 1 LAST TOLERANCE 1%
J 0
(-4730 4100);
DISPLAY 0.617021 (-4730 4100);
PAINT SKYBLUE (-4730 4100);
FORCEPROP 1 LAST PACK_TYPE 0402
J 0
(-4735 3900);
DISPLAY 0.617021 (-4735 3900);
PAINT SKYBLUE (-4735 3900);
FORCEPROP 1 LASTPIN (-4775 4175) $PN 1
J 0
(-4770 4137);
DISPLAY 0.617021 (-4770 4137);
PAINT ORANGE (-4770 4137);
FORCEPROP 1 LAST LOCATION R9B8
J 0
(-4730 4200);
DISPLAY 0.617021 (-4730 4200);
PAINT AQUA (-4730 4200);
FORCEPROP 1 LAST WATTAGE 1/16W
J 0
(-4735 4050);
DISPLAY 0.617021 (-4735 4050);
PAINT SKYBLUE (-4735 4050);
FORCEPROP 1 LAST VALUE 1.00K
J 0
(-4730 4150);
DISPLAY 0.617021 (-4730 4150);
PAINT SKYBLUE (-4730 4150);
FORCEPROP 1 LAST PART_NUMBER G21796-026
J 0
(-4735 3950);
DISPLAY 0.617021 (-4735 3950);
PAINT BLUE (-4735 3950);
FORCEPROP 2 LAST CDS_LIB mstr_discrete
J 0
(-4775 4075);
PAINT ORANGE (-4775 4075);
DISPLAY INVISIBLE (-4775 4075);
FORCEPROP 2 LAST BOM_COST SM_THERM
J 0
(-4725 4300);
DISPLAY 1.021277 (-4725 4300);
PAINT ORANGE (-4725 4300);
DISPLAY INVISIBLE (-4725 4300);
FORCEPROP 2 LAST SEC_TYPE 0402
J 0
(-4725 4300);
DISPLAY 1.021277 (-4725 4300);
PAINT ORANGE (-4725 4300);
DISPLAY INVISIBLE (-4725 4300);
FORCEPROP 0 LAST SEC 1
J 0
(-4725 4250);
DISPLAY 0.680851 (-4725 4250);
PAINT MONO (-4725 4250);
DISPLAY INVISIBLE (-4725 4250);
FORCEPROP 2 LAST CDS_LOCATION R9B8
J 0
(-4730 4200);
DISPLAY 0.617021 (-4730 4200);
PAINT AQUA (-4730 4200);
DISPLAY INVISIBLE (-4730 4200);
FORCEPROP 1 LAST PATH I10
J 0
(-4725 4250);
DISPLAY 0.978723 (-4725 4250);
PAINT WHITE (-4725 4250);
DISPLAY INVISIBLE (-4725 4250);
FORCEPROP 2 LAST ROOM TEMP_SENSORS
J 0
(-4725 4250);
DISPLAY 1.021277 (-4725 4250);
PAINT ORANGE (-4725 4250);
DISPLAY INVISIBLE (-4725 4250);
FORCEADD GND..1
(-4775 3850);
FORCEPROP 3 LASTPIN (-4775 3900) SIG_NAME GND\g
J 0
(-4765 3910);
DISPLAY 0.659574 (-4765 3910);
PAINT MONO (-4765 3910);
DISPLAY INVISIBLE (-4765 3910);
FORCEPROP 1 LAST SIZE 1B
J 0
(-4700 3800);
DISPLAY 0.872340 (-4700 3800);
PAINT AQUA (-4700 3800);
DISPLAY INVISIBLE (-4700 3800);
FORCEPROP 1 LAST VOLTAGE 0.0V
J 0
(-4820 3807);
DISPLAY 0.340426 (-4820 3807);
PAINT SKYBLUE (-4820 3807);
DISPLAY INVISIBLE (-4820 3807);
FORCEPROP 2 LAST CDS_LIB mstr_symbols
J 0
(-4775 3850);
PAINT ORANGE (-4775 3850);
DISPLAY INVISIBLE (-4775 3850);
FORCEPROP 1 LAST PATH I12
J 0
(-4700 3850);
DISPLAY 0.872340 (-4700 3850);
PAINT AQUA (-4700 3850);
DISPLAY INVISIBLE (-4700 3850);
FORCEPROP 1 LAST BODY_TYPE PLUMBING
J 0
(-4820 3807);
DISPLAY 0.340426 (-4820 3807);
PAINT GREEN (-4820 3807);
DISPLAY INVISIBLE (-4820 3807);
FORCEPROP 1 LAST HDL_POWER GND
J 0
(-4775 4000);
DISPLAY 0.872340 (-4775 4000);
PAINT GREEN (-4775 4000);
DISPLAY INVISIBLE (-4775 4000);
FORCEADD P3V3_STBY..1
(-4350 5150);
FORCEPROP 3 LASTPIN (-4350 5100) SIG_NAME P3V3_STBY\g
J 0
(-4340 5110);
DISPLAY 0.659574 (-4340 5110);
PAINT MONO (-4340 5110);
DISPLAY INVISIBLE (-4340 5110);
FORCEPROP 1 LAST VOLTAGE 3.3V
J 0
(-4395 5107);
DISPLAY 0.340426 (-4395 5107);
PAINT SKYBLUE (-4395 5107);
DISPLAY INVISIBLE (-4395 5107);
FORCEPROP 1 LAST PATH I14
J 0
(-4305 5152);
DISPLAY 0.340426 (-4305 5152);
PAINT GREEN (-4305 5152);
DISPLAY INVISIBLE (-4305 5152);
FORCEPROP 1 LAST SIZE 1B
J 0
(-4305 5172);
DISPLAY 0.340426 (-4305 5172);
PAINT GREEN (-4305 5172);
DISPLAY INVISIBLE (-4305 5172);
FORCEPROP 2 LAST CDS_LIB mstr_symbols
J 0
(-4350 5150);
PAINT ORANGE (-4350 5150);
DISPLAY INVISIBLE (-4350 5150);
FORCEPROP 1 LAST BODY_TYPE PLUMBING
J 0
(-4395 5107);
DISPLAY 0.340426 (-4395 5107);
PAINT GREEN (-4395 5107);
DISPLAY INVISIBLE (-4395 5107);
FORCEPROP 1 LAST HDL_POWER P3V3_STBY
J 0
(-4650 5025);
DISPLAY 0.872340 (-4650 5025);
PAINT ORANGE (-4650 5025);
DISPLAY INVISIBLE (-4650 5025);
FORCEADD GND..1
(-3400 3850);
FORCEPROP 3 LASTPIN (-3400 3900) SIG_NAME GND\g
J 0
(-3390 3910);
DISPLAY 0.659574 (-3390 3910);
PAINT MONO (-3390 3910);
DISPLAY INVISIBLE (-3390 3910);
FORCEPROP 1 LAST PATH I15
J 0
(-3325 3850);
DISPLAY 0.872340 (-3325 3850);
PAINT AQUA (-3325 3850);
DISPLAY INVISIBLE (-3325 3850);
FORCEPROP 1 LAST SIZE 1B
J 0
(-3325 3800);
DISPLAY 0.872340 (-3325 3800);
PAINT AQUA (-3325 3800);
DISPLAY INVISIBLE (-3325 3800);
FORCEPROP 2 LAST CDS_LIB mstr_symbols
J 0
(-3400 3850);
PAINT ORANGE (-3400 3850);
DISPLAY INVISIBLE (-3400 3850);
FORCEPROP 1 LAST VOLTAGE 0.0V
J 0
(-3445 3807);
DISPLAY 0.340426 (-3445 3807);
PAINT SKYBLUE (-3445 3807);
DISPLAY INVISIBLE (-3445 3807);
FORCEPROP 1 LAST BODY_TYPE PLUMBING
J 0
(-3445 3807);
DISPLAY 0.340426 (-3445 3807);
PAINT GREEN (-3445 3807);
DISPLAY INVISIBLE (-3445 3807);
FORCEPROP 1 LAST HDL_POWER GND
J 0
(-3400 4000);
DISPLAY 0.872340 (-3400 4000);
PAINT GREEN (-3400 4000);
DISPLAY INVISIBLE (-3400 4000);
FORCEADD OFFPAGE..4
(-1150 4500);
FORCEPROP 2 LAST $XR3 191 
J 0
(-604 4500);
DISPLAY 0.638298 (-604 4500);
PAINT MONO (-604 4500);
FORCEPROP 2 LAST $XR2 184 
J 0
(-724 4500);
DISPLAY 0.638298 (-724 4500);
PAINT MONO (-724 4500);
FORCEPROP 2 LAST $XR1 167 
J 0
(-844 4500);
DISPLAY 0.638298 (-844 4500);
PAINT MONO (-844 4500);
FORCEPROP 2 LAST $XR0 164 
J 0
(-964 4500);
DISPLAY 0.638298 (-964 4500);
PAINT MONO (-964 4500);
FORCEPROP 2 LAST CDS_LIB mstr_standard
J 0
(-1150 4500);
PAINT ORANGE (-1150 4500);
DISPLAY INVISIBLE (-1150 4500);
FORCEPROP 2 LAST PATH I16
J 0
(-1100 4575);
DISPLAY 1.021277 (-1100 4575);
PAINT ORANGE (-1100 4575);
DISPLAY INVISIBLE (-1100 4575);
FORCEPROP 1 LAST OFFPAGE TRUE
J 0
(-825 4375);
DISPLAY 0.872340 (-825 4375);
PAINT GREEN (-825 4375);
DISPLAY INVISIBLE (-825 4375);
FORCEPROP 1 LAST COMMENT_BODY TRUE
J 0
(-1175 4400);
DISPLAY 0.872340 (-1175 4400);
PAINT GREEN (-1175 4400);
DISPLAY INVISIBLE (-1175 4400);
FORCEADD OFFPAGE..3
(-1150 4450);
FORCEPROP 2 LAST $XR3 191 
J 0
(-576 4450);
DISPLAY 0.638298 (-576 4450);
PAINT MONO (-576 4450);
FORCEPROP 2 LAST $XR2 184 
J 0
(-696 4450);
DISPLAY 0.638298 (-696 4450);
PAINT MONO (-696 4450);
FORCEPROP 2 LAST $XR1 164 
J 0
(-816 4450);
DISPLAY 0.638298 (-816 4450);
PAINT MONO (-816 4450);
FORCEPROP 2 LAST $XR0 167 
J 0
(-936 4450);
DISPLAY 0.638298 (-936 4450);
PAINT MONO (-936 4450);
FORCEPROP 2 LAST CDS_LIB mstr_standard
J 0
(-1150 4450);
PAINT ORANGE (-1150 4450);
DISPLAY INVISIBLE (-1150 4450);
FORCEPROP 2 LAST PATH I17
J 0
(-1100 4525);
DISPLAY 1.021277 (-1100 4525);
PAINT ORANGE (-1100 4525);
DISPLAY INVISIBLE (-1100 4525);
FORCEPROP 1 LAST OFFPAGE TRUE
J 0
(-825 4325);
DISPLAY 0.872340 (-825 4325);
PAINT GREEN (-825 4325);
DISPLAY INVISIBLE (-825 4325);
FORCEPROP 1 LAST COMMENT_BODY TRUE
J 0
(-1200 4350);
DISPLAY 0.872340 (-1200 4350);
PAINT GREEN (-1200 4350);
DISPLAY INVISIBLE (-1200 4350);
FORCEADD GND..1
(-3225 2400);
FORCEPROP 3 LASTPIN (-3225 2450) SIG_NAME GND\g
J 0
(-3215 2460);
DISPLAY 0.659574 (-3215 2460);
PAINT MONO (-3215 2460);
DISPLAY INVISIBLE (-3215 2460);
FORCEPROP 1 LAST PATH I22
J 0
(-3150 2400);
DISPLAY 0.872340 (-3150 2400);
PAINT AQUA (-3150 2400);
DISPLAY INVISIBLE (-3150 2400);
FORCEPROP 2 LAST CDS_LIB mstr_symbols
J 0
(-3225 2400);
PAINT ORANGE (-3225 2400);
DISPLAY INVISIBLE (-3225 2400);
FORCEPROP 1 LAST SIZE 1B
J 0
(-3150 2350);
DISPLAY 0.872340 (-3150 2350);
PAINT AQUA (-3150 2350);
DISPLAY INVISIBLE (-3150 2350);
FORCEPROP 1 LAST VOLTAGE 0.0V
J 0
(-3270 2357);
DISPLAY 0.340426 (-3270 2357);
PAINT SKYBLUE (-3270 2357);
DISPLAY INVISIBLE (-3270 2357);
FORCEPROP 1 LAST BODY_TYPE PLUMBING
J 0
(-3270 2357);
DISPLAY 0.340426 (-3270 2357);
PAINT GREEN (-3270 2357);
DISPLAY INVISIBLE (-3270 2357);
FORCEPROP 1 LAST HDL_POWER GND
J 0
(-3225 2550);
DISPLAY 0.872340 (-3225 2550);
PAINT GREEN (-3225 2550);
DISPLAY INVISIBLE (-3225 2550);
FORCEADD P3V3_STBY..1
(-4175 3700);
FORCEPROP 3 LASTPIN (-4175 3650) SIG_NAME P3V3_STBY\g
J 0
(-4165 3660);
DISPLAY 0.659574 (-4165 3660);
PAINT MONO (-4165 3660);
DISPLAY INVISIBLE (-4165 3660);
FORCEPROP 1 LAST PATH I23
J 0
(-4130 3702);
DISPLAY 0.340426 (-4130 3702);
PAINT GREEN (-4130 3702);
DISPLAY INVISIBLE (-4130 3702);
FORCEPROP 2 LAST CDS_LIB mstr_symbols
J 0
(-4175 3700);
PAINT ORANGE (-4175 3700);
DISPLAY INVISIBLE (-4175 3700);
FORCEPROP 1 LAST SIZE 1B
J 0
(-4130 3722);
DISPLAY 0.340426 (-4130 3722);
PAINT GREEN (-4130 3722);
DISPLAY INVISIBLE (-4130 3722);
FORCEPROP 1 LAST VOLTAGE 3.3V
J 0
(-4220 3657);
DISPLAY 0.340426 (-4220 3657);
PAINT SKYBLUE (-4220 3657);
DISPLAY INVISIBLE (-4220 3657);
FORCEPROP 1 LAST BODY_TYPE PLUMBING
J 0
(-4220 3657);
DISPLAY 0.340426 (-4220 3657);
PAINT GREEN (-4220 3657);
DISPLAY INVISIBLE (-4220 3657);
FORCEPROP 1 LAST HDL_POWER P3V3_STBY
J 0
(-4475 3575);
DISPLAY 0.872340 (-4475 3575);
PAINT ORANGE (-4475 3575);
DISPLAY INVISIBLE (-4475 3575);
FORCEADD CAP..1
(-4675 3175);
FORCEPROP 1 LAST PART_NUMBER A36095-025
J 0
(-4625 3050);
DISPLAY 0.617021 (-4625 3050);
PAINT BLUE (-4625 3050);
FORCEPROP 1 LAST PACK_TYPE 0402LF
J 0
(-4550 3125);
DISPLAY 0.617021 (-4550 3125);
PAINT SKYBLUE (-4550 3125);
FORCEPROP 1 LAST VOLTAGE 50V
J 0
(-4625 3175);
DISPLAY 0.617021 (-4625 3175);
PAINT SKYBLUE (-4625 3175);
FORCEPROP 1 LAST TOLERANCE 5%
J 0
(-4625 3125);
DISPLAY 0.617021 (-4625 3125);
PAINT SKYBLUE (-4625 3125);
FORCEPROP 1 LAST VALUE 47.0PF
J 0
(-4625 3225);
DISPLAY 0.617021 (-4625 3225);
PAINT SKYBLUE (-4625 3225);
FORCEPROP 1 LAST LOCATION C1E19
J 0
(-4625 3275);
DISPLAY 0.617021 (-4625 3275);
PAINT AQUA (-4625 3275);
FORCEPROP 1 LASTPIN (-4675 3275) $PN 1
J 0
(-4665 3255);
DISPLAY 0.617021 (-4665 3255);
PAINT ORANGE (-4665 3255);
FORCEPROP 1 LASTPIN (-4675 3075) $PN 2
J 0
(-4665 3055);
DISPLAY 0.617021 (-4665 3055);
PAINT ORANGE (-4665 3055);
FORCEPROP 1 LAST MATERIAL EMPTY
J 0
(-4550 3075);
DISPLAY 0.617021 (-4550 3075);
PAINT RED (-4550 3075);
FORCEPROP 2 LAST CDS_LIB mstr_discrete
J 0
(-4675 3175);
PAINT ORANGE (-4675 3175);
DISPLAY INVISIBLE (-4675 3175);
FORCEPROP 2 LAST CDS_LOCATION C1E19
J 0
(-4625 3275);
DISPLAY 0.617021 (-4625 3275);
PAINT AQUA (-4625 3275);
DISPLAY INVISIBLE (-4625 3275);
FORCEPROP 2 LAST ROOM TEMP_SENSORS
J 0
(-4625 3325);
DISPLAY 1.021277 (-4625 3325);
PAINT ORANGE (-4625 3325);
DISPLAY INVISIBLE (-4625 3325);
FORCEPROP 1 LAST PATH I24
J 0
(-4625 3325);
DISPLAY 0.978723 (-4625 3325);
PAINT WHITE (-4625 3325);
DISPLAY INVISIBLE (-4625 3325);
FORCEPROP 0 LAST SEC 1
J 0
(-4625 3325);
DISPLAY 0.680851 (-4625 3325);
PAINT MONO (-4625 3325);
DISPLAY INVISIBLE (-4625 3325);
FORCEPROP 2 LAST BOM_COST SM_THERM
J 0
(-4625 3375);
DISPLAY 1.021277 (-4625 3375);
PAINT ORANGE (-4625 3375);
DISPLAY INVISIBLE (-4625 3375);
FORCEPROP 2 LAST SEC_TYPE 0402LF
J 0
(-4625 3375);
DISPLAY 1.021277 (-4625 3375);
PAINT ORANGE (-4625 3375);
DISPLAY INVISIBLE (-4625 3375);
FORCEADD RES..1
(-5000 3325);
FORCEPROP 1 LAST PACK_TYPE 0402
J 0
(-4925 3225);
DISPLAY 0.617021 (-4925 3225);
PAINT SKYBLUE (-4925 3225);
FORCEPROP 1 LAST TOLERANCE 1%
J 0
(-5000 3225);
DISPLAY 0.617021 (-5000 3225);
PAINT SKYBLUE (-5000 3225);
FORCEPROP 1 LAST VALUE 49.9
J 2
(-5025 3225);
DISPLAY 0.617021 (-5025 3225);
PAINT SKYBLUE (-5025 3225);
FORCEPROP 1 LAST WATTAGE 1/16W
J 2
(-5025 3175);
DISPLAY 0.617021 (-5025 3175);
PAINT SKYBLUE (-5025 3175);
FORCEPROP 1 LAST LOCATION R9R5
J 0
(-5050 3375);
DISPLAY 0.617021 (-5050 3375);
PAINT AQUA (-5050 3375);
FORCEPROP 1 LASTPIN (-5100 3325) $PN 1
J 0
(-5088 3337);
DISPLAY 0.617021 (-5088 3337);
PAINT ORANGE (-5088 3337);
FORCEPROP 1 LASTPIN (-4900 3325) $PN 2
J 0
(-4938 3337);
DISPLAY 0.617021 (-4938 3337);
PAINT ORANGE (-4938 3337);
FORCEPROP 1 LAST PART_NUMBER G21796-047
J 0
(-5050 3425);
DISPLAY 0.617021 (-5050 3425);
PAINT BLUE (-5050 3425);
FORCEPROP 1 LAST MATERIAL CHIP
J 0
(-5000 3175);
DISPLAY 0.617021 (-5000 3175);
PAINT SKYBLUE (-5000 3175);
FORCEPROP 2 LAST CDS_LIB mstr_discrete
J 0
(-5000 3325);
PAINT ORANGE (-5000 3325);
DISPLAY INVISIBLE (-5000 3325);
FORCEPROP 2 LAST ROOM TEMP_SENSORS
J 0
(-5050 3475);
DISPLAY 1.021277 (-5050 3475);
PAINT ORANGE (-5050 3475);
DISPLAY INVISIBLE (-5050 3475);
FORCEPROP 1 LAST PATH I25
J 0
(-5050 3475);
DISPLAY 0.978723 (-5050 3475);
PAINT WHITE (-5050 3475);
DISPLAY INVISIBLE (-5050 3475);
FORCEPROP 2 LAST CDS_LOCATION R9R5
J 0
(-5050 3375);
DISPLAY 0.617021 (-5050 3375);
PAINT AQUA (-5050 3375);
DISPLAY INVISIBLE (-5050 3375);
FORCEPROP 0 LAST SEC 1
J 0
(-5050 3475);
DISPLAY 0.680851 (-5050 3475);
PAINT MONO (-5050 3475);
DISPLAY INVISIBLE (-5050 3475);
FORCEPROP 2 LAST BOM_COST SM_THERM
J 0
(-5050 3525);
DISPLAY 1.021277 (-5050 3525);
PAINT ORANGE (-5050 3525);
DISPLAY INVISIBLE (-5050 3525);
FORCEPROP 2 LAST SEC_TYPE 0402
J 0
(-5050 3525);
DISPLAY 1.021277 (-5050 3525);
PAINT ORANGE (-5050 3525);
DISPLAY INVISIBLE (-5050 3525);
FORCEADD RES..1
(-4975 3000);
FORCEPROP 1 LAST PACK_TYPE 0402
J 0
(-5075 2950);
DISPLAY 0.617021 (-5075 2950);
PAINT SKYBLUE (-5075 2950);
FORCEPROP 1 LASTPIN (-4875 3000) $PN 2
J 0
(-4913 3012);
DISPLAY 0.617021 (-4913 3012);
PAINT ORANGE (-4913 3012);
FORCEPROP 1 LAST PART_NUMBER G21796-047
J 0
(-5025 3100);
DISPLAY 0.617021 (-5025 3100);
PAINT BLUE (-5025 3100);
FORCEPROP 1 LAST WATTAGE 1/16W
J 2
(-4750 2950);
DISPLAY 0.617021 (-4750 2950);
PAINT SKYBLUE (-4750 2950);
FORCEPROP 1 LAST TOLERANCE 1%
J 0
(-4925 2950);
DISPLAY 0.617021 (-4925 2950);
PAINT SKYBLUE (-4925 2950);
FORCEPROP 1 LASTPIN (-5075 3000) $PN 1
J 0
(-5063 3012);
DISPLAY 0.617021 (-5063 3012);
PAINT ORANGE (-5063 3012);
FORCEPROP 1 LAST LOCATION R9R6
J 0
(-5025 3050);
DISPLAY 0.617021 (-5025 3050);
PAINT AQUA (-5025 3050);
FORCEPROP 1 LAST MATERIAL CHIP
J 0
(-5375 2950);
DISPLAY 0.617021 (-5375 2950);
PAINT SKYBLUE (-5375 2950);
FORCEPROP 1 LAST VALUE 49.9
J 2
(-5150 2950);
DISPLAY 0.617021 (-5150 2950);
PAINT SKYBLUE (-5150 2950);
FORCEPROP 2 LAST CDS_LIB mstr_discrete
J 0
(-4975 3000);
PAINT ORANGE (-4975 3000);
DISPLAY INVISIBLE (-4975 3000);
FORCEPROP 2 LAST CDS_LOCATION R9R6
J 0
(-5025 3050);
DISPLAY 0.617021 (-5025 3050);
PAINT AQUA (-5025 3050);
DISPLAY INVISIBLE (-5025 3050);
FORCEPROP 2 LAST ROOM TEMP_SENSORS
J 0
(-5025 3150);
DISPLAY 1.021277 (-5025 3150);
PAINT ORANGE (-5025 3150);
DISPLAY INVISIBLE (-5025 3150);
FORCEPROP 2 LAST BOM_COST SM_THERM
J 0
(-5025 3200);
DISPLAY 1.021277 (-5025 3200);
PAINT ORANGE (-5025 3200);
DISPLAY INVISIBLE (-5025 3200);
FORCEPROP 2 LAST SEC_TYPE 0402
J 0
(-5025 3200);
DISPLAY 1.021277 (-5025 3200);
PAINT ORANGE (-5025 3200);
DISPLAY INVISIBLE (-5025 3200);
FORCEPROP 0 LAST SEC 1
J 0
(-5025 3150);
DISPLAY 0.680851 (-5025 3150);
PAINT MONO (-5025 3150);
DISPLAY INVISIBLE (-5025 3150);
FORCEPROP 1 LAST PATH I26
J 0
(-5025 3150);
DISPLAY 0.978723 (-5025 3150);
PAINT WHITE (-5025 3150);
DISPLAY INVISIBLE (-5025 3150);
FORCEADD P3V3_STBY..1
(-6400 3075);
FORCEPROP 3 LASTPIN (-6400 3025) SIG_NAME P3V3_STBY\g
J 0
(-6390 3035);
DISPLAY 0.659574 (-6390 3035);
PAINT MONO (-6390 3035);
DISPLAY INVISIBLE (-6390 3035);
FORCEPROP 1 LAST VOLTAGE 3.3V
J 0
(-6445 3032);
DISPLAY 0.340426 (-6445 3032);
PAINT SKYBLUE (-6445 3032);
DISPLAY INVISIBLE (-6445 3032);
FORCEPROP 1 LAST PATH I29
J 0
(-6355 3077);
DISPLAY 0.340426 (-6355 3077);
PAINT GREEN (-6355 3077);
DISPLAY INVISIBLE (-6355 3077);
FORCEPROP 1 LAST SIZE 1B
J 0
(-6355 3097);
DISPLAY 0.340426 (-6355 3097);
PAINT GREEN (-6355 3097);
DISPLAY INVISIBLE (-6355 3097);
FORCEPROP 2 LAST CDS_LIB mstr_symbols
J 0
(-6400 3075);
PAINT ORANGE (-6400 3075);
DISPLAY INVISIBLE (-6400 3075);
FORCEPROP 1 LAST BODY_TYPE PLUMBING
J 0
(-6445 3032);
DISPLAY 0.340426 (-6445 3032);
PAINT GREEN (-6445 3032);
DISPLAY INVISIBLE (-6445 3032);
FORCEPROP 1 LAST HDL_POWER P3V3_STBY
J 0
(-6700 2950);
DISPLAY 0.872340 (-6700 2950);
PAINT ORANGE (-6700 2950);
DISPLAY INVISIBLE (-6700 2950);
FORCEADD TMP421..1
(-3825 3000);
FORCEPROP 1 LAST LOCATION U1E1
J 0
(-4075 3400);
DISPLAY 0.617021 (-4075 3400);
PAINT AQUA (-4075 3400);
FORCEPROP 1 LAST PART_NUMBER G62962-001
J 0
(-4075 2700);
DISPLAY 0.617021 (-4075 2700);
PAINT BLUE (-4075 2700);
FORCEPROP 2 LASTPIN (-4125 3050) $PN 1
J 2
(-4135 3060);
DISPLAY 0.617021 (-4135 3060);
PAINT ORANGE (-4135 3060);
FORCEPROP 2 LASTPIN (-4125 2850) $PN 4
J 2
(-4135 2860);
DISPLAY 0.617021 (-4135 2860);
PAINT ORANGE (-4135 2860);
FORCEPROP 2 LASTPIN (-4125 2900) $PN 3
J 2
(-4135 2910);
DISPLAY 0.617021 (-4135 2910);
PAINT ORANGE (-4135 2910);
FORCEPROP 2 LASTPIN (-4125 3000) $PN 2
J 2
(-4135 3010);
DISPLAY 0.617021 (-4135 3010);
PAINT ORANGE (-4135 3010);
FORCEPROP 2 LASTPIN (-3525 3000) $PN 7
J 0
(-3515 3010);
DISPLAY 0.617021 (-3515 3010);
PAINT ORANGE (-3515 3010);
FORCEPROP 2 LASTPIN (-3525 3050) $PN 6
J 0
(-3515 3060);
DISPLAY 0.617021 (-3515 3060);
PAINT ORANGE (-3515 3060);
FORCEPROP 2 LASTPIN (-3525 2800) $PN 5
J 0
(-3515 2810);
DISPLAY 0.617021 (-3515 2810);
PAINT ORANGE (-3515 2810);
FORCEPROP 2 LASTPIN (-4125 3150) $PN 8
J 2
(-4135 3160);
DISPLAY 0.617021 (-4135 3160);
PAINT ORANGE (-4135 3160);
FORCEPROP 1 LAST MATERIAL IC
J 0
(-4075 3350);
DISPLAY 0.617021 (-4075 3350);
PAINT SKYBLUE (-4075 3350);
FORCEPROP 2 LAST CDS_LIB mstr_analog
J 0
(-3825 3000);
PAINT ORANGE (-3825 3000);
DISPLAY INVISIBLE (-3825 3000);
FORCEPROP 2 LAST ROOM TEMP_SENSORS
J 0
(-4075 3450);
DISPLAY 1.021277 (-4075 3450);
PAINT ORANGE (-4075 3450);
DISPLAY INVISIBLE (-4075 3450);
FORCEPROP 1 LAST PATH I30
J 0
(-3825 3350);
PAINT GREEN (-3825 3350);
DISPLAY INVISIBLE (-3825 3350);
FORCEPROP 2 LAST CDS_LOCATION U1E1
J 0
(-4075 3400);
DISPLAY 0.617021 (-4075 3400);
PAINT AQUA (-4075 3400);
DISPLAY INVISIBLE (-4075 3400);
FORCEPROP 2 LAST SEC 1
J 0
(-4075 3450);
DISPLAY 0.680851 (-4075 3450);
PAINT MONO (-4075 3450);
DISPLAY INVISIBLE (-4075 3450);
FORCEPROP 2 LAST BOM_COST SM_THERM
J 0
(-4075 3500);
DISPLAY 1.021277 (-4075 3500);
PAINT ORANGE (-4075 3500);
DISPLAY INVISIBLE (-4075 3500);
FORCEPROP 2 LAST SEC_TYPE TSSOP
J 0
(-4075 3450);
DISPLAY 1.021277 (-4075 3450);
PAINT ORANGE (-4075 3450);
DISPLAY INVISIBLE (-4075 3450);
FORCEPROP 1 LAST PACK_TYPE TSSOP
J 0
(-4075 3450);
PAINT SKYBLUE (-4075 3450);
DISPLAY INVISIBLE (-4075 3450);
FORCEADD RES..1
(-5050 2850);
FORCEPROP 1 LAST LOCATION R1E9
J 0
(-5100 2900);
DISPLAY 0.617021 (-5100 2900);
PAINT AQUA (-5100 2900);
FORCEPROP 1 LAST PACK_TYPE 0402
J 0
(-5175 2600);
DISPLAY 0.617021 (-5175 2600);
PAINT SKYBLUE (-5175 2600);
FORCEPROP 1 LAST MATERIAL CHIP
J 0
(-5050 2700);
DISPLAY 0.617021 (-5050 2700);
PAINT SKYBLUE (-5050 2700);
FORCEPROP 1 LAST TOLERANCE 1%
J 0
(-5050 2750);
DISPLAY 0.617021 (-5050 2750);
PAINT SKYBLUE (-5050 2750);
FORCEPROP 1 LAST VALUE 1.00K
J 2
(-5075 2750);
DISPLAY 0.617021 (-5075 2750);
PAINT SKYBLUE (-5075 2750);
FORCEPROP 1 LAST WATTAGE 1/16W
J 2
(-5075 2700);
DISPLAY 0.617021 (-5075 2700);
PAINT SKYBLUE (-5075 2700);
FORCEPROP 1 LAST PART_NUMBER G21796-026
J 0
(-5175 2650);
DISPLAY 0.617021 (-5175 2650);
PAINT BLUE (-5175 2650);
FORCEPROP 1 LASTPIN (-4950 2850) $PN 2
J 0
(-4988 2862);
DISPLAY 0.617021 (-4988 2862);
PAINT ORANGE (-4988 2862);
FORCEPROP 1 LASTPIN (-5150 2850) $PN 1
J 0
(-5138 2862);
DISPLAY 0.617021 (-5138 2862);
PAINT ORANGE (-5138 2862);
FORCEPROP 2 LAST CDS_LIB mstr_discrete
J 0
(-5050 2850);
PAINT MONO (-5050 2850);
DISPLAY INVISIBLE (-5050 2850);
FORCEPROP 2 LAST CDS_LOCATION R1E9
J 0
(-5100 2900);
DISPLAY 0.617021 (-5100 2900);
PAINT AQUA (-5100 2900);
DISPLAY INVISIBLE (-5100 2900);
FORCEPROP 1 LAST PATH I34
J 0
(-5100 3000);
DISPLAY 0.978723 (-5100 3000);
PAINT WHITE (-5100 3000);
DISPLAY INVISIBLE (-5100 3000);
FORCEPROP 2 LAST ROOM TEMP_SENSORS
J 0
(-5100 3000);
DISPLAY 1.021277 (-5100 3000);
PAINT ORANGE (-5100 3000);
DISPLAY INVISIBLE (-5100 3000);
FORCEPROP 2 LAST SEC 1
J 0
(-5100 3050);
DISPLAY 0.680851 (-5100 3050);
PAINT MONO (-5100 3050);
DISPLAY INVISIBLE (-5100 3050);
FORCEPROP 2 LAST BOM_COST SM_THERM
J 0
(-5100 3050);
DISPLAY 1.021277 (-5100 3050);
PAINT ORANGE (-5100 3050);
DISPLAY INVISIBLE (-5100 3050);
FORCEPROP 2 LAST SEC_TYPE 0402
J 0
(-5100 3050);
DISPLAY 1.021277 (-5100 3050);
PAINT ORANGE (-5100 3050);
DISPLAY INVISIBLE (-5100 3050);
FORCEADD RES..1
(-5475 4150);
FORCEPROP 1 LAST MATERIAL CHIP
J 0
(-5500 4100);
DISPLAY 0.617021 (-5500 4100);
PAINT SKYBLUE (-5500 4100);
FORCEPROP 1 LAST PART_NUMBER G21796-026
J 0
(-5350 4150);
DISPLAY 0.617021 (-5350 4150);
PAINT BLUE (-5350 4150);
FORCEPROP 1 LAST TOLERANCE 1%
J 0
(-5400 4100);
DISPLAY 0.617021 (-5400 4100);
PAINT SKYBLUE (-5400 4100);
FORCEPROP 1 LASTPIN (-5375 4150) $PN 2
J 0
(-5413 4162);
DISPLAY 0.617021 (-5413 4162);
PAINT ORANGE (-5413 4162);
FORCEPROP 1 LAST PACK_TYPE 0402
J 0
(-5325 4100);
DISPLAY 0.617021 (-5325 4100);
PAINT SKYBLUE (-5325 4100);
FORCEPROP 1 LAST VALUE 1.00K
J 2
(-5500 4100);
DISPLAY 0.617021 (-5500 4100);
PAINT SKYBLUE (-5500 4100);
FORCEPROP 1 LAST WATTAGE 1/16W
J 2
(-5600 4100);
DISPLAY 0.617021 (-5600 4100);
PAINT SKYBLUE (-5600 4100);
FORCEPROP 1 LAST LOCATION R9B6
J 0
(-5700 4150);
DISPLAY 0.617021 (-5700 4150);
PAINT AQUA (-5700 4150);
FORCEPROP 1 LASTPIN (-5575 4150) $PN 1
J 0
(-5563 4162);
DISPLAY 0.617021 (-5563 4162);
PAINT ORANGE (-5563 4162);
FORCEPROP 2 LAST BOM_COST SM_THERM
J 0
(-5425 4375);
DISPLAY 1.021277 (-5425 4375);
PAINT ORANGE (-5425 4375);
DISPLAY INVISIBLE (-5425 4375);
FORCEPROP 2 LAST ROOM TEMP_SENSORS
J 0
(-5425 4325);
DISPLAY 1.021277 (-5425 4325);
PAINT ORANGE (-5425 4325);
DISPLAY INVISIBLE (-5425 4325);
FORCEPROP 1 LAST PATH I35
J 0
(-5525 4300);
DISPLAY 0.978723 (-5525 4300);
PAINT WHITE (-5525 4300);
DISPLAY INVISIBLE (-5525 4300);
FORCEPROP 2 LAST SEC 1
J 0
(-5525 4350);
DISPLAY 0.680851 (-5525 4350);
PAINT MONO (-5525 4350);
DISPLAY INVISIBLE (-5525 4350);
FORCEPROP 2 LAST SEC_TYPE 0402
J 0
(-5525 4350);
DISPLAY 1.021277 (-5525 4350);
PAINT ORANGE (-5525 4350);
DISPLAY INVISIBLE (-5525 4350);
FORCEPROP 2 LAST CDS_LIB mstr_discrete
J 0
(-5475 4150);
PAINT ORANGE (-5475 4150);
DISPLAY INVISIBLE (-5475 4150);
FORCEPROP 2 LAST CDS_LOCATION R9B6
J 0
(-5700 4150);
DISPLAY 0.617021 (-5700 4150);
PAINT AQUA (-5700 4150);
DISPLAY INVISIBLE (-5700 4150);
FORCEADD RES..1
(-4650 2900);
FORCEPROP 1 LAST PART_NUMBER G21796-026
J 0
(-4775 2700);
DISPLAY 0.617021 (-4775 2700);
PAINT BLUE (-4775 2700);
FORCEPROP 1 LAST WATTAGE 1/16W
J 2
(-4675 2750);
DISPLAY 0.617021 (-4675 2750);
PAINT SKYBLUE (-4675 2750);
FORCEPROP 1 LAST LOCATION R1E10
J 0
(-4500 2800);
DISPLAY 0.617021 (-4500 2800);
PAINT AQUA (-4500 2800);
FORCEPROP 1 LAST TOLERANCE 1%
J 0
(-4650 2800);
DISPLAY 0.617021 (-4650 2800);
PAINT SKYBLUE (-4650 2800);
FORCEPROP 1 LAST MATERIAL CHIP
J 0
(-4650 2750);
DISPLAY 0.617021 (-4650 2750);
PAINT SKYBLUE (-4650 2750);
FORCEPROP 1 LASTPIN (-4750 2900) $PN 1
J 0
(-4738 2912);
DISPLAY 0.617021 (-4738 2912);
PAINT ORANGE (-4738 2912);
FORCEPROP 1 LAST VALUE 1.00K
J 2
(-4675 2800);
DISPLAY 0.617021 (-4675 2800);
PAINT SKYBLUE (-4675 2800);
FORCEPROP 1 LASTPIN (-4550 2900) $PN 2
J 0
(-4588 2912);
DISPLAY 0.617021 (-4588 2912);
PAINT ORANGE (-4588 2912);
FORCEPROP 1 LAST PACK_TYPE 0402
J 0
(-4750 2650);
DISPLAY 0.617021 (-4750 2650);
PAINT SKYBLUE (-4750 2650);
FORCEPROP 2 LAST CDS_LIB mstr_discrete
J 0
(-4650 2900);
PAINT ORANGE (-4650 2900);
DISPLAY INVISIBLE (-4650 2900);
FORCEPROP 2 LAST CDS_LOCATION R1E10
J 0
(-4700 2950);
DISPLAY 0.617021 (-4700 2950);
PAINT AQUA (-4700 2950);
DISPLAY INVISIBLE (-4700 2950);
FORCEPROP 2 LAST ROOM TEMP_SENSORS
J 0
(-4700 3000);
DISPLAY 1.021277 (-4700 3000);
PAINT ORANGE (-4700 3000);
DISPLAY INVISIBLE (-4700 3000);
FORCEPROP 1 LAST PATH I38
J 0
(-4700 3050);
DISPLAY 0.978723 (-4700 3050);
PAINT WHITE (-4700 3050);
DISPLAY INVISIBLE (-4700 3050);
FORCEPROP 2 LAST BOM_COST SM_THERM
J 0
(-4700 3050);
DISPLAY 1.021277 (-4700 3050);
PAINT ORANGE (-4700 3050);
DISPLAY INVISIBLE (-4700 3050);
FORCEPROP 2 LAST SEC 1
J 0
(-4700 3100);
PAINT MONO (-4700 3100);
DISPLAY INVISIBLE (-4700 3100);
FORCEPROP 2 LAST SEC_TYPE 0402
J 0
(-4700 3100);
DISPLAY 1.021277 (-4700 3100);
PAINT ORANGE (-4700 3100);
DISPLAY INVISIBLE (-4700 3100);
FORCEADD CAP_A..1
(-7700 4350);
FORCEPROP 1 LAST LOCATION C9B7
J 0
(-7650 4450);
DISPLAY 0.617021 (-7650 4450);
PAINT AQUA (-7650 4450);
FORCEPROP 1 LAST VOLTAGE 16V
J 0
(-7650 4350);
DISPLAY 0.617021 (-7650 4350);
PAINT SKYBLUE (-7650 4350);
FORCEPROP 1 LAST TOLERANCE 10%
J 0
(-7650 4300);
DISPLAY 0.617021 (-7650 4300);
PAINT SKYBLUE (-7650 4300);
FORCEPROP 1 LAST MATERIAL X7R
J 0
(-7650 4250);
DISPLAY 0.617021 (-7650 4250);
PAINT SKYBLUE (-7650 4250);
FORCEPROP 1 LAST PART_NUMBER A36096-030
J 0
(-7650 4200);
DISPLAY 0.617021 (-7650 4200);
PAINT BLUE (-7650 4200);
FORCEPROP 1 LAST PACK_TYPE 0402V
J 0
(-7650 4150);
DISPLAY 0.617021 (-7650 4150);
PAINT SKYBLUE (-7650 4150);
FORCEPROP 1 LASTPIN (-7700 4250) $PN 2
J 0
(-7690 4230);
DISPLAY 0.617021 (-7690 4230);
PAINT ORANGE (-7690 4230);
FORCEPROP 1 LASTPIN (-7700 4450) $PN 1
J 0
(-7690 4430);
DISPLAY 0.617021 (-7690 4430);
PAINT ORANGE (-7690 4430);
FORCEPROP 1 LAST VALUE 0.1UF
J 0
(-7650 4400);
DISPLAY 0.617021 (-7650 4400);
PAINT SKYBLUE (-7650 4400);
FORCEPROP 2 LAST CDS_LIB dev_discrete
J 0
(-7700 4350);
PAINT ORANGE (-7700 4350);
DISPLAY INVISIBLE (-7700 4350);
FORCEPROP 1 LAST PATH I39
J 0
(-7650 4500);
DISPLAY 0.978723 (-7650 4500);
PAINT WHITE (-7650 4500);
DISPLAY INVISIBLE (-7650 4500);
FORCEPROP 2 LAST ROOM TEMP_SENSORS
J 0
(-7650 4500);
DISPLAY 1.021277 (-7650 4500);
PAINT ORANGE (-7650 4500);
DISPLAY INVISIBLE (-7650 4500);
FORCEPROP 2 LAST CDS_LOCATION C9B7
J 0
(-7650 4450);
DISPLAY 0.617021 (-7650 4450);
PAINT AQUA (-7650 4450);
DISPLAY INVISIBLE (-7650 4450);
FORCEPROP 2 LAST BOM_COST SM_THERM
J 0
(-7650 4550);
DISPLAY 1.021277 (-7650 4550);
PAINT ORANGE (-7650 4550);
DISPLAY INVISIBLE (-7650 4550);
FORCEPROP 2 LAST CDS_SEC 1
J 0
(-7650 4500);
PAINT ORANGE (-7650 4500);
DISPLAY INVISIBLE (-7650 4500);
FORCEPROP 2 LAST SEC_TYPE 0402V
J 0
(-7650 4550);
DISPLAY 1.021277 (-7650 4550);
PAINT ORANGE (-7650 4550);
DISPLAY INVISIBLE (-7650 4550);
FORCEPROP 2 LAST SEC 1
J 0
(-7650 4550);
PAINT MONO (-7650 4550);
DISPLAY INVISIBLE (-7650 4550);
FORCEADD CAP_A..1
(-7700 3675);
FORCEPROP 1 LAST LOCATION C9R14
J 0
(-7650 3775);
DISPLAY 0.617021 (-7650 3775);
PAINT AQUA (-7650 3775);
FORCEPROP 1 LASTPIN (-7700 3575) $PN 2
J 0
(-7690 3555);
DISPLAY 0.617021 (-7690 3555);
PAINT ORANGE (-7690 3555);
FORCEPROP 1 LASTPIN (-7700 3775) $PN 1
J 0
(-7690 3755);
DISPLAY 0.617021 (-7690 3755);
PAINT ORANGE (-7690 3755);
FORCEPROP 1 LAST PACK_TYPE 0402V
J 0
(-7650 3475);
DISPLAY 0.617021 (-7650 3475);
PAINT SKYBLUE (-7650 3475);
FORCEPROP 1 LAST PART_NUMBER A36096-030
J 0
(-7650 3525);
DISPLAY 0.617021 (-7650 3525);
PAINT BLUE (-7650 3525);
FORCEPROP 1 LAST MATERIAL X7R
J 0
(-7650 3575);
DISPLAY 0.617021 (-7650 3575);
PAINT SKYBLUE (-7650 3575);
FORCEPROP 1 LAST VALUE 0.1UF
J 0
(-7650 3725);
DISPLAY 0.617021 (-7650 3725);
PAINT SKYBLUE (-7650 3725);
FORCEPROP 1 LAST TOLERANCE 10%
J 0
(-7650 3625);
DISPLAY 0.617021 (-7650 3625);
PAINT SKYBLUE (-7650 3625);
FORCEPROP 1 LAST VOLTAGE 16V
J 0
(-7650 3675);
DISPLAY 0.617021 (-7650 3675);
PAINT SKYBLUE (-7650 3675);
FORCEPROP 2 LAST CDS_LIB dev_discrete
J 0
(-7700 3675);
PAINT ORANGE (-7700 3675);
DISPLAY INVISIBLE (-7700 3675);
FORCEPROP 1 LAST PATH I41
J 0
(-7650 3825);
DISPLAY 0.978723 (-7650 3825);
PAINT WHITE (-7650 3825);
DISPLAY INVISIBLE (-7650 3825);
FORCEPROP 2 LAST ROOM TEMP_SENSORS
J 0
(-7650 3825);
DISPLAY 1.021277 (-7650 3825);
PAINT ORANGE (-7650 3825);
DISPLAY INVISIBLE (-7650 3825);
FORCEPROP 2 LAST CDS_LOCATION C9R14
J 0
(-7650 3775);
DISPLAY 0.617021 (-7650 3775);
PAINT AQUA (-7650 3775);
DISPLAY INVISIBLE (-7650 3775);
FORCEPROP 2 LAST BOM_COST SM_THERM
J 0
(-7650 3875);
DISPLAY 1.021277 (-7650 3875);
PAINT ORANGE (-7650 3875);
DISPLAY INVISIBLE (-7650 3875);
FORCEPROP 2 LAST CDS_SEC 1
J 0
(-7650 3825);
PAINT ORANGE (-7650 3825);
DISPLAY INVISIBLE (-7650 3825);
FORCEPROP 2 LAST SEC_TYPE 0402V
J 0
(-7650 3875);
DISPLAY 1.021277 (-7650 3875);
PAINT ORANGE (-7650 3875);
DISPLAY INVISIBLE (-7650 3875);
FORCEPROP 2 LAST SEC 1
J 0
(-7650 3875);
PAINT MONO (-7650 3875);
DISPLAY INVISIBLE (-7650 3875);
FORCEADD CAP_A..1
(-1425 2150);
FORCEPROP 1 LASTPIN (-1425 2050) $PN 2
J 0
(-1415 2030);
DISPLAY 0.617021 (-1415 2030);
PAINT ORANGE (-1415 2030);
FORCEPROP 1 LASTPIN (-1425 2250) $PN 1
J 0
(-1415 2230);
DISPLAY 0.617021 (-1415 2230);
PAINT ORANGE (-1415 2230);
FORCEPROP 1 LAST PART_NUMBER A36096-030
J 0
(-1375 2000);
DISPLAY 0.617021 (-1375 2000);
PAINT BLUE (-1375 2000);
FORCEPROP 1 LAST MATERIAL X7R
J 0
(-1375 2050);
DISPLAY 0.617021 (-1375 2050);
PAINT SKYBLUE (-1375 2050);
FORCEPROP 1 LAST LOCATION C9R13
J 0
(-1375 2250);
DISPLAY 0.617021 (-1375 2250);
PAINT AQUA (-1375 2250);
FORCEPROP 1 LAST VALUE 0.1UF
J 0
(-1375 2200);
DISPLAY 0.617021 (-1375 2200);
PAINT SKYBLUE (-1375 2200);
FORCEPROP 1 LAST VOLTAGE 16V
J 0
(-1375 2150);
DISPLAY 0.617021 (-1375 2150);
PAINT SKYBLUE (-1375 2150);
FORCEPROP 1 LAST TOLERANCE 10%
J 0
(-1375 2100);
DISPLAY 0.617021 (-1375 2100);
PAINT SKYBLUE (-1375 2100);
FORCEPROP 1 LAST PACK_TYPE 0402V
J 0
(-1375 1950);
DISPLAY 0.617021 (-1375 1950);
PAINT SKYBLUE (-1375 1950);
FORCEPROP 2 LAST CDS_LIB dev_discrete
J 0
(-1425 2150);
PAINT ORANGE (-1425 2150);
DISPLAY INVISIBLE (-1425 2150);
FORCEPROP 2 LAST CDS_LOCATION C9R13
J 0
(-1375 2250);
DISPLAY 0.617021 (-1375 2250);
PAINT AQUA (-1375 2250);
DISPLAY INVISIBLE (-1375 2250);
FORCEPROP 2 LAST CDS_SEC 1
J 0
(-1375 2300);
PAINT ORANGE (-1375 2300);
DISPLAY INVISIBLE (-1375 2300);
FORCEPROP 2 LAST ROOM TEMP_SENSORS
J 0
(-1375 2300);
DISPLAY 1.021277 (-1375 2300);
PAINT ORANGE (-1375 2300);
DISPLAY INVISIBLE (-1375 2300);
FORCEPROP 1 LAST PATH I42
J 0
(-1375 2300);
DISPLAY 0.978723 (-1375 2300);
PAINT WHITE (-1375 2300);
DISPLAY INVISIBLE (-1375 2300);
FORCEPROP 2 LAST SEC 1
J 0
(-1375 2350);
PAINT MONO (-1375 2350);
DISPLAY INVISIBLE (-1375 2350);
FORCEPROP 2 LAST SEC_TYPE 0402V
J 0
(-1375 2350);
DISPLAY 1.021277 (-1375 2350);
PAINT ORANGE (-1375 2350);
DISPLAY INVISIBLE (-1375 2350);
FORCEPROP 2 LAST BOM_COST SM_THERM
J 0
(-1375 2350);
DISPLAY 1.021277 (-1375 2350);
PAINT ORANGE (-1375 2350);
DISPLAY INVISIBLE (-1375 2350);
FORCEADD GND..1
(-7700 3350);
FORCEPROP 3 LASTPIN (-7700 3400) SIG_NAME GND\g
J 0
(-7690 3410);
DISPLAY 0.659574 (-7690 3410);
PAINT MONO (-7690 3410);
DISPLAY INVISIBLE (-7690 3410);
FORCEPROP 2 LAST CDS_LIB mstr_symbols
J 0
(-7700 3350);
PAINT ORANGE (-7700 3350);
DISPLAY INVISIBLE (-7700 3350);
FORCEPROP 1 LAST VOLTAGE 0.0V
J 0
(-7745 3307);
DISPLAY 0.340426 (-7745 3307);
PAINT SKYBLUE (-7745 3307);
DISPLAY INVISIBLE (-7745 3307);
FORCEPROP 1 LAST SIZE 1B
J 0
(-7625 3300);
DISPLAY 0.872340 (-7625 3300);
PAINT AQUA (-7625 3300);
DISPLAY INVISIBLE (-7625 3300);
FORCEPROP 1 LAST PATH I45
J 0
(-7625 3350);
DISPLAY 0.872340 (-7625 3350);
PAINT AQUA (-7625 3350);
DISPLAY INVISIBLE (-7625 3350);
FORCEPROP 1 LAST BODY_TYPE PLUMBING
J 0
(-7745 3307);
DISPLAY 0.340426 (-7745 3307);
PAINT GREEN (-7745 3307);
DISPLAY INVISIBLE (-7745 3307);
FORCEPROP 1 LAST HDL_POWER GND
J 0
(-7700 3500);
DISPLAY 0.872340 (-7700 3500);
PAINT GREEN (-7700 3500);
DISPLAY INVISIBLE (-7700 3500);
FORCEADD GND..1
(-1425 1825);
FORCEPROP 3 LASTPIN (-1425 1875) SIG_NAME GND\g
J 0
(-1415 1885);
DISPLAY 0.659574 (-1415 1885);
PAINT MONO (-1415 1885);
DISPLAY INVISIBLE (-1415 1885);
FORCEPROP 1 LAST SIZE 1B
J 0
(-1350 1775);
DISPLAY 0.872340 (-1350 1775);
PAINT AQUA (-1350 1775);
DISPLAY INVISIBLE (-1350 1775);
FORCEPROP 1 LAST VOLTAGE 0.0V
J 0
(-1470 1782);
DISPLAY 0.340426 (-1470 1782);
PAINT SKYBLUE (-1470 1782);
DISPLAY INVISIBLE (-1470 1782);
FORCEPROP 1 LAST PATH I46
J 0
(-1350 1825);
DISPLAY 0.872340 (-1350 1825);
PAINT AQUA (-1350 1825);
DISPLAY INVISIBLE (-1350 1825);
FORCEPROP 2 LAST CDS_LIB mstr_symbols
J 0
(-1425 1825);
PAINT ORANGE (-1425 1825);
DISPLAY INVISIBLE (-1425 1825);
FORCEPROP 1 LAST BODY_TYPE PLUMBING
J 0
(-1470 1782);
DISPLAY 0.340426 (-1470 1782);
PAINT GREEN (-1470 1782);
DISPLAY INVISIBLE (-1470 1782);
FORCEPROP 1 LAST HDL_POWER GND
J 0
(-1425 1975);
DISPLAY 0.872340 (-1425 1975);
PAINT GREEN (-1425 1975);
DISPLAY INVISIBLE (-1425 1975);
FORCEADD GND..1
(-7700 4100);
FORCEPROP 3 LASTPIN (-7700 4150) SIG_NAME GND\g
J 0
(-7690 4160);
DISPLAY 0.659574 (-7690 4160);
PAINT MONO (-7690 4160);
DISPLAY INVISIBLE (-7690 4160);
FORCEPROP 1 LAST VOLTAGE 0.0V
J 0
(-7745 4057);
DISPLAY 0.340426 (-7745 4057);
PAINT SKYBLUE (-7745 4057);
DISPLAY INVISIBLE (-7745 4057);
FORCEPROP 1 LAST SIZE 1B
J 0
(-7625 4050);
DISPLAY 0.872340 (-7625 4050);
PAINT AQUA (-7625 4050);
DISPLAY INVISIBLE (-7625 4050);
FORCEPROP 2 LAST CDS_LIB mstr_symbols
J 0
(-7700 4100);
PAINT ORANGE (-7700 4100);
DISPLAY INVISIBLE (-7700 4100);
FORCEPROP 1 LAST PATH I47
J 0
(-7625 4100);
DISPLAY 0.872340 (-7625 4100);
PAINT AQUA (-7625 4100);
DISPLAY INVISIBLE (-7625 4100);
FORCEPROP 1 LAST BODY_TYPE PLUMBING
J 0
(-7745 4057);
DISPLAY 0.340426 (-7745 4057);
PAINT GREEN (-7745 4057);
DISPLAY INVISIBLE (-7745 4057);
FORCEPROP 1 LAST HDL_POWER GND
J 0
(-7700 4250);
DISPLAY 0.872340 (-7700 4250);
PAINT GREEN (-7700 4250);
DISPLAY INVISIBLE (-7700 4250);
FORCEADD AT24C64..1
(-2700 1650);
FORCEPROP 1 LAST MATERIAL IC
J 0
(-2950 1950);
DISPLAY 0.617021 (-2950 1950);
PAINT SKYBLUE (-2950 1950);
FORCEPROP 1 LAST PART_NUMBER C47049-001
J 0
(-2950 1300);
DISPLAY 0.617021 (-2950 1300);
PAINT BLUE (-2950 1300);
FORCEPROP 2 LASTPIN (-3000 1750) $PN 3
J 2
(-3010 1760);
DISPLAY 0.617021 (-3010 1760);
PAINT ORANGE (-3010 1760);
FORCEPROP 1 LAST LOCATION U8D4
J 0
(-2950 2000);
DISPLAY 0.617021 (-2950 2000);
PAINT AQUA (-2950 2000);
FORCEPROP 2 LASTPIN (-3000 1700) $PN 2
J 2
(-3010 1710);
DISPLAY 0.617021 (-3010 1710);
PAINT ORANGE (-3010 1710);
FORCEPROP 2 LASTPIN (-3000 1550) $PN 6
J 2
(-3010 1560);
DISPLAY 0.617021 (-3010 1560);
PAINT ORANGE (-3010 1560);
FORCEPROP 2 LASTPIN (-2400 1550) $PN 5
J 0
(-2390 1560);
DISPLAY 0.617021 (-2390 1560);
PAINT ORANGE (-2390 1560);
FORCEPROP 2 LASTPIN (-3000 1650) $PN 1
J 2
(-3010 1660);
DISPLAY 0.617021 (-3010 1660);
PAINT ORANGE (-3010 1660);
FORCEPROP 1 LAST POWER_GROUP VCC=P3V3_STBY;GND=GND;
J 0
(-2950 1250);
DISPLAY 0.617021 (-2950 1250);
PAINT ORANGE (-2950 1250);
FORCEPROP 2 LASTPIN (-3000 1500) $PN 7
J 2
(-3010 1510);
DISPLAY 0.617021 (-3010 1510);
PAINT ORANGE (-3010 1510);
FORCEPROP 2 LAST CDS_LOCATION U8D4
J 0
(-2950 2000);
DISPLAY 0.617021 (-2950 2000);
PAINT AQUA (-2950 2000);
DISPLAY INVISIBLE (-2950 2000);
FORCEPROP 2 LAST CDS_LIB mstr_memory
J 0
(-2700 1650);
PAINT ORANGE (-2700 1650);
DISPLAY INVISIBLE (-2700 1650);
FORCEPROP 1 LAST PATH I49
J 0
(-2525 1950);
DISPLAY 0.957447 (-2525 1950);
PAINT PURPLE (-2525 1950);
DISPLAY INVISIBLE (-2525 1950);
FORCEPROP 2 LAST ROOM TEMP_SENSORS
J 0
(-2950 2050);
DISPLAY 1.021277 (-2950 2050);
PAINT ORANGE (-2950 2050);
DISPLAY INVISIBLE (-2950 2050);
FORCEPROP 1 LAST PACK_TYPE SOICLF
J 0
(-2950 2050);
DISPLAY 0.957447 (-2950 2050);
PAINT SKYBLUE (-2950 2050);
DISPLAY INVISIBLE (-2950 2050);
FORCEPROP 2 LAST SEC_TYPE SOICLF
J 0
(-2950 2050);
DISPLAY 1.021277 (-2950 2050);
PAINT ORANGE (-2950 2050);
DISPLAY INVISIBLE (-2950 2050);
FORCEPROP 2 LAST BOM_COST SM_THERM
J 0
(-2950 2100);
DISPLAY 1.021277 (-2950 2100);
PAINT ORANGE (-2950 2100);
DISPLAY INVISIBLE (-2950 2100);
FORCEPROP 2 LAST SEC 1
J 0
(-2950 2050);
DISPLAY 0.680851 (-2950 2050);
PAINT MONO (-2950 2050);
DISPLAY INVISIBLE (-2950 2050);
FORCEADD RES..1
(-5150 4450);
FORCEPROP 1 LAST VALUE 49.9
J 2
(-5200 4400);
DISPLAY 0.617021 (-5200 4400);
PAINT SKYBLUE (-5200 4400);
FORCEPROP 1 LAST MATERIAL CHIP
J 0
(-5175 4400);
DISPLAY 0.617021 (-5175 4400);
PAINT SKYBLUE (-5175 4400);
FORCEPROP 1 LAST LOCATION R9B5
J 0
(-5200 4500);
DISPLAY 0.617021 (-5200 4500);
PAINT AQUA (-5200 4500);
FORCEPROP 1 LASTPIN (-5050 4450) $PN 2
J 0
(-5088 4462);
DISPLAY 0.617021 (-5088 4462);
PAINT ORANGE (-5088 4462);
FORCEPROP 1 LASTPIN (-5250 4450) $PN 1
J 0
(-5238 4462);
DISPLAY 0.617021 (-5238 4462);
PAINT ORANGE (-5238 4462);
FORCEPROP 1 LAST TOLERANCE 1%
J 0
(-5075 4400);
DISPLAY 0.617021 (-5075 4400);
PAINT SKYBLUE (-5075 4400);
FORCEPROP 1 LAST PACK_TYPE 0402
J 0
(-5400 4350);
DISPLAY 0.617021 (-5400 4350);
PAINT SKYBLUE (-5400 4350);
FORCEPROP 1 LAST WATTAGE 1/16W
J 2
(-5300 4400);
DISPLAY 0.617021 (-5300 4400);
PAINT SKYBLUE (-5300 4400);
FORCEPROP 1 LAST PART_NUMBER G21796-047
J 0
(-5200 4550);
DISPLAY 0.617021 (-5200 4550);
PAINT BLUE (-5200 4550);
FORCEPROP 1 LAST PATH I5
J 0
(-5200 4600);
DISPLAY 0.978723 (-5200 4600);
PAINT WHITE (-5200 4600);
DISPLAY INVISIBLE (-5200 4600);
FORCEPROP 2 LAST BOM_COST SM_THERM
J 0
(-5200 4650);
DISPLAY 1.021277 (-5200 4650);
PAINT ORANGE (-5200 4650);
DISPLAY INVISIBLE (-5200 4650);
FORCEPROP 2 LAST SEC_TYPE 0402
J 0
(-5200 4650);
DISPLAY 1.021277 (-5200 4650);
PAINT ORANGE (-5200 4650);
DISPLAY INVISIBLE (-5200 4650);
FORCEPROP 0 LAST SEC 1
J 0
(-5200 4600);
DISPLAY 0.680851 (-5200 4600);
PAINT MONO (-5200 4600);
DISPLAY INVISIBLE (-5200 4600);
FORCEPROP 2 LAST ROOM TEMP_SENSORS
J 0
(-5200 4600);
DISPLAY 1.021277 (-5200 4600);
PAINT ORANGE (-5200 4600);
DISPLAY INVISIBLE (-5200 4600);
FORCEPROP 2 LAST CDS_LIB mstr_discrete
J 0
(-5150 4450);
PAINT ORANGE (-5150 4450);
DISPLAY INVISIBLE (-5150 4450);
FORCEPROP 2 LAST CDS_LOCATION R9B5
J 0
(-5200 4500);
DISPLAY 0.617021 (-5200 4500);
PAINT AQUA (-5200 4500);
DISPLAY INVISIBLE (-5200 4500);
FORCEADD RES..2
(-3500 1300);
FORCEPROP 1 LAST TOLERANCE 1%
J 0
(-3455 1325);
DISPLAY 0.617021 (-3455 1325);
PAINT SKYBLUE (-3455 1325);
FORCEPROP 1 LAST VALUE 1.00K
J 0
(-3455 1375);
DISPLAY 0.617021 (-3455 1375);
PAINT SKYBLUE (-3455 1375);
FORCEPROP 1 LASTPIN (-3500 1400) $PN 1
J 0
(-3495 1362);
DISPLAY 0.617021 (-3495 1362);
PAINT ORANGE (-3495 1362);
FORCEPROP 1 LAST LOCATION R8D27
J 0
(-3455 1425);
DISPLAY 0.617021 (-3455 1425);
PAINT AQUA (-3455 1425);
FORCEPROP 1 LASTPIN (-3500 1200) $PN 2
J 0
(-3495 1210);
DISPLAY 0.617021 (-3495 1210);
PAINT ORANGE (-3495 1210);
FORCEPROP 1 LAST PACK_TYPE 0402
J 0
(-3460 1125);
DISPLAY 0.617021 (-3460 1125);
PAINT SKYBLUE (-3460 1125);
FORCEPROP 1 LAST WATTAGE 1/16W
J 0
(-3460 1275);
DISPLAY 0.617021 (-3460 1275);
PAINT SKYBLUE (-3460 1275);
FORCEPROP 1 LAST MATERIAL CHIP
J 0
(-3460 1225);
DISPLAY 0.617021 (-3460 1225);
PAINT SKYBLUE (-3460 1225);
FORCEPROP 1 LAST PART_NUMBER G21796-026
J 0
(-3460 1175);
DISPLAY 0.617021 (-3460 1175);
PAINT BLUE (-3460 1175);
FORCEPROP 2 LAST CDS_LIB mstr_discrete
J 0
(-3500 1300);
PAINT ORANGE (-3500 1300);
DISPLAY INVISIBLE (-3500 1300);
FORCEPROP 0 LAST SEC 1
J 0
(-3450 1475);
DISPLAY 0.680851 (-3450 1475);
PAINT MONO (-3450 1475);
DISPLAY INVISIBLE (-3450 1475);
FORCEPROP 2 LAST CDS_LOCATION R8D27
J 0
(-3455 1425);
DISPLAY 0.617021 (-3455 1425);
PAINT AQUA (-3455 1425);
DISPLAY INVISIBLE (-3455 1425);
FORCEPROP 1 LAST PATH I50
J 0
(-3450 1475);
DISPLAY 0.978723 (-3450 1475);
PAINT WHITE (-3450 1475);
DISPLAY INVISIBLE (-3450 1475);
FORCEPROP 2 LAST ROOM TEMP_SENSORS
J 0
(-3450 1475);
DISPLAY 1.021277 (-3450 1475);
PAINT ORANGE (-3450 1475);
DISPLAY INVISIBLE (-3450 1475);
FORCEPROP 2 LAST BOM_COST SM_THERM
J 0
(-3450 1525);
DISPLAY 1.021277 (-3450 1525);
PAINT ORANGE (-3450 1525);
DISPLAY INVISIBLE (-3450 1525);
FORCEPROP 2 LAST SEC_TYPE 0402
J 0
(-3450 1525);
DISPLAY 1.021277 (-3450 1525);
PAINT ORANGE (-3450 1525);
DISPLAY INVISIBLE (-3450 1525);
FORCEADD GND..1
(-3500 1050);
FORCEPROP 3 LASTPIN (-3500 1100) SIG_NAME GND\g
J 0
(-3490 1110);
DISPLAY 0.659574 (-3490 1110);
PAINT MONO (-3490 1110);
DISPLAY INVISIBLE (-3490 1110);
FORCEPROP 1 LAST VOLTAGE 0.0V
J 0
(-3545 1007);
DISPLAY 0.340426 (-3545 1007);
PAINT SKYBLUE (-3545 1007);
DISPLAY INVISIBLE (-3545 1007);
FORCEPROP 1 LAST SIZE 1B
J 0
(-3425 1000);
DISPLAY 0.872340 (-3425 1000);
PAINT AQUA (-3425 1000);
DISPLAY INVISIBLE (-3425 1000);
FORCEPROP 2 LAST CDS_LIB mstr_symbols
J 0
(-3500 1050);
PAINT ORANGE (-3500 1050);
DISPLAY INVISIBLE (-3500 1050);
FORCEPROP 1 LAST PATH I52
J 0
(-3425 1050);
DISPLAY 0.872340 (-3425 1050);
PAINT AQUA (-3425 1050);
DISPLAY INVISIBLE (-3425 1050);
FORCEPROP 1 LAST BODY_TYPE PLUMBING
J 0
(-3545 1007);
DISPLAY 0.340426 (-3545 1007);
PAINT GREEN (-3545 1007);
DISPLAY INVISIBLE (-3545 1007);
FORCEPROP 1 LAST HDL_POWER GND
J 0
(-3500 1200);
DISPLAY 0.872340 (-3500 1200);
PAINT GREEN (-3500 1200);
DISPLAY INVISIBLE (-3500 1200);
FORCEADD GND..1
(-3075 1050);
FORCEPROP 3 LASTPIN (-3075 1100) SIG_NAME GND\g
J 0
(-3065 1110);
DISPLAY 0.659574 (-3065 1110);
PAINT MONO (-3065 1110);
DISPLAY INVISIBLE (-3065 1110);
FORCEPROP 1 LAST VOLTAGE 0.0V
J 0
(-3120 1007);
DISPLAY 0.340426 (-3120 1007);
PAINT SKYBLUE (-3120 1007);
DISPLAY INVISIBLE (-3120 1007);
FORCEPROP 2 LAST CDS_LIB mstr_symbols
J 0
(-3075 1050);
PAINT ORANGE (-3075 1050);
DISPLAY INVISIBLE (-3075 1050);
FORCEPROP 1 LAST SIZE 1B
J 0
(-3000 1000);
DISPLAY 0.872340 (-3000 1000);
PAINT AQUA (-3000 1000);
DISPLAY INVISIBLE (-3000 1000);
FORCEPROP 1 LAST PATH I55
J 0
(-3000 1050);
DISPLAY 0.872340 (-3000 1050);
PAINT AQUA (-3000 1050);
DISPLAY INVISIBLE (-3000 1050);
FORCEPROP 1 LAST BODY_TYPE PLUMBING
J 0
(-3120 1007);
DISPLAY 0.340426 (-3120 1007);
PAINT GREEN (-3120 1007);
DISPLAY INVISIBLE (-3120 1007);
FORCEPROP 1 LAST HDL_POWER GND
J 0
(-3075 1200);
DISPLAY 0.872340 (-3075 1200);
PAINT GREEN (-3075 1200);
DISPLAY INVISIBLE (-3075 1200);
FORCEADD P3V3_STBY..1
(-7700 4650);
FORCEPROP 3 LASTPIN (-7700 4600) SIG_NAME P3V3_STBY\g
J 0
(-7690 4610);
DISPLAY 0.659574 (-7690 4610);
PAINT MONO (-7690 4610);
DISPLAY INVISIBLE (-7690 4610);
FORCEPROP 1 LAST VOLTAGE 3.3V
J 0
(-7745 4607);
DISPLAY 0.340426 (-7745 4607);
PAINT SKYBLUE (-7745 4607);
DISPLAY INVISIBLE (-7745 4607);
FORCEPROP 2 LAST CDS_LIB mstr_symbols
J 0
(-7700 4650);
PAINT ORANGE (-7700 4650);
DISPLAY INVISIBLE (-7700 4650);
FORCEPROP 1 LAST SIZE 1B
J 0
(-7655 4672);
DISPLAY 0.340426 (-7655 4672);
PAINT GREEN (-7655 4672);
DISPLAY INVISIBLE (-7655 4672);
FORCEPROP 1 LAST PATH I56
J 0
(-7655 4652);
DISPLAY 0.340426 (-7655 4652);
PAINT GREEN (-7655 4652);
DISPLAY INVISIBLE (-7655 4652);
FORCEPROP 1 LAST BODY_TYPE PLUMBING
J 0
(-7745 4607);
DISPLAY 0.340426 (-7745 4607);
PAINT GREEN (-7745 4607);
DISPLAY INVISIBLE (-7745 4607);
FORCEPROP 1 LAST HDL_POWER P3V3_STBY
J 0
(-8000 4525);
DISPLAY 0.872340 (-8000 4525);
PAINT ORANGE (-8000 4525);
DISPLAY INVISIBLE (-8000 4525);
FORCEADD P3V3_STBY..1
(-7700 3950);
FORCEPROP 3 LASTPIN (-7700 3900) SIG_NAME P3V3_STBY\g
J 0
(-7690 3910);
DISPLAY 0.659574 (-7690 3910);
PAINT MONO (-7690 3910);
DISPLAY INVISIBLE (-7690 3910);
FORCEPROP 2 LAST CDS_LIB mstr_symbols
J 0
(-7700 3950);
PAINT ORANGE (-7700 3950);
DISPLAY INVISIBLE (-7700 3950);
FORCEPROP 1 LAST VOLTAGE 3.3V
J 0
(-7745 3907);
DISPLAY 0.340426 (-7745 3907);
PAINT SKYBLUE (-7745 3907);
DISPLAY INVISIBLE (-7745 3907);
FORCEPROP 1 LAST SIZE 1B
J 0
(-7655 3972);
DISPLAY 0.340426 (-7655 3972);
PAINT GREEN (-7655 3972);
DISPLAY INVISIBLE (-7655 3972);
FORCEPROP 1 LAST PATH I57
J 0
(-7655 3952);
DISPLAY 0.340426 (-7655 3952);
PAINT GREEN (-7655 3952);
DISPLAY INVISIBLE (-7655 3952);
FORCEPROP 1 LAST BODY_TYPE PLUMBING
J 0
(-7745 3907);
DISPLAY 0.340426 (-7745 3907);
PAINT GREEN (-7745 3907);
DISPLAY INVISIBLE (-7745 3907);
FORCEPROP 1 LAST HDL_POWER P3V3_STBY
J 0
(-8000 3825);
DISPLAY 0.872340 (-8000 3825);
PAINT ORANGE (-8000 3825);
DISPLAY INVISIBLE (-8000 3825);
FORCEADD RES..1
(-6725 1450);
FORCEPROP 1 LAST PART_NUMBER G21796-173
J 0
(-6475 1400);
DISPLAY 0.617021 (-6475 1400);
PAINT BLUE (-6475 1400);
FORCEPROP 1 LAST WATTAGE 1/16W
J 0
(-6225 1400);
DISPLAY 0.617021 (-6225 1400);
PAINT SKYBLUE (-6225 1400);
FORCEPROP 1 LAST PACK_TYPE 0402
J 0
(-6050 1400);
DISPLAY 0.617021 (-6050 1400);
PAINT SKYBLUE (-6050 1400);
FORCEPROP 1 LASTPIN (-6625 1450) $PN 2
J 0
(-6663 1462);
DISPLAY 0.617021 (-6663 1462);
PAINT ORANGE (-6663 1462);
FORCEPROP 1 LAST MATERIAL CHIP
J 0
(-6575 1400);
DISPLAY 0.617021 (-6575 1400);
PAINT SKYBLUE (-6575 1400);
FORCEPROP 1 LAST TOLERANCE 1%
J 0
(-6650 1400);
DISPLAY 0.617021 (-6650 1400);
PAINT SKYBLUE (-6650 1400);
FORCEPROP 1 LAST VALUE 20.0
J 2
(-6775 1400);
DISPLAY 0.617021 (-6775 1400);
PAINT SKYBLUE (-6775 1400);
FORCEPROP 1 LAST LOCATION R9G15
J 0
(-7025 1400);
DISPLAY 0.617021 (-7025 1400);
PAINT AQUA (-7025 1400);
FORCEPROP 1 LASTPIN (-6825 1450) $PN 1
J 0
(-6813 1462);
DISPLAY 0.617021 (-6813 1462);
PAINT ORANGE (-6813 1462);
FORCEPROP 2 LAST CDS_LIB mstr_discrete
J 0
(-6725 1450);
PAINT MONO (-6725 1450);
DISPLAY INVISIBLE (-6725 1450);
FORCEPROP 1 LAST PATH I58
J 0
(-6775 1600);
DISPLAY 0.978723 (-6775 1600);
PAINT WHITE (-6775 1600);
DISPLAY INVISIBLE (-6775 1600);
FORCEPROP 2 LAST CDS_LOCATION R9G15
J 0
(-6750 1550);
DISPLAY 0.617021 (-6750 1550);
PAINT AQUA (-6750 1550);
DISPLAY INVISIBLE (-6750 1550);
FORCEPROP 2 LAST $SEC 1
J 0
(-6775 1650);
PAINT MONO (-6775 1650);
DISPLAY INVISIBLE (-6775 1650);
FORCEPROP 2 LAST CDS_SEC 1
J 0
(-6775 1650);
PAINT MONO (-6775 1650);
DISPLAY INVISIBLE (-6775 1650);
FORCEPROP 0 LAST ROOM SMBUS
J 0
(-6475 1500);
DISPLAY 1.021277 (-6475 1500);
PAINT ORANGE (-6475 1500);
DISPLAY INVISIBLE (-6475 1500);
FORCEPROP 0 LAST SKU B
J 0
(-6475 1500);
DISPLAY 1.021277 (-6475 1500);
PAINT ORANGE (-6475 1500);
DISPLAY INVISIBLE (-6475 1500);
FORCEPROP 0 LAST BOM_COST SM_CONTROLLER
J 0
(-6475 1600);
DISPLAY 1.021277 (-6475 1600);
PAINT ORANGE (-6475 1600);
DISPLAY INVISIBLE (-6475 1600);
FORCEADD RES..1
(-5150 4775);
FORCEPROP 1 LAST PACK_TYPE 0402
J 0
(-5075 4700);
DISPLAY 0.617021 (-5075 4700);
PAINT SKYBLUE (-5075 4700);
FORCEPROP 1 LAST TOLERANCE 1%
J 0
(-5150 4675);
DISPLAY 0.617021 (-5150 4675);
PAINT SKYBLUE (-5150 4675);
FORCEPROP 1 LAST VALUE 49.9
J 2
(-5175 4675);
DISPLAY 0.617021 (-5175 4675);
PAINT SKYBLUE (-5175 4675);
FORCEPROP 1 LAST MATERIAL CHIP
J 0
(-5150 4625);
DISPLAY 0.617021 (-5150 4625);
PAINT SKYBLUE (-5150 4625);
FORCEPROP 1 LASTPIN (-5250 4775) $PN 1
J 0
(-5238 4787);
DISPLAY 0.617021 (-5238 4787);
PAINT ORANGE (-5238 4787);
FORCEPROP 1 LASTPIN (-5050 4775) $PN 2
J 0
(-5088 4787);
DISPLAY 0.617021 (-5088 4787);
PAINT ORANGE (-5088 4787);
FORCEPROP 1 LAST WATTAGE 1/16W
J 2
(-5175 4625);
DISPLAY 0.617021 (-5175 4625);
PAINT SKYBLUE (-5175 4625);
FORCEPROP 1 LAST PART_NUMBER G21796-047
J 0
(-5200 4875);
DISPLAY 0.617021 (-5200 4875);
PAINT BLUE (-5200 4875);
FORCEPROP 1 LAST LOCATION R9B4
J 0
(-5200 4825);
DISPLAY 0.617021 (-5200 4825);
PAINT AQUA (-5200 4825);
FORCEPROP 2 LAST CDS_LIB mstr_discrete
J 0
(-5150 4775);
PAINT ORANGE (-5150 4775);
DISPLAY INVISIBLE (-5150 4775);
FORCEPROP 2 LAST CDS_LOCATION R9B4
J 0
(-5200 4825);
DISPLAY 0.617021 (-5200 4825);
PAINT AQUA (-5200 4825);
DISPLAY INVISIBLE (-5200 4825);
FORCEPROP 2 LAST ROOM TEMP_SENSORS
J 0
(-5200 4925);
DISPLAY 1.021277 (-5200 4925);
PAINT ORANGE (-5200 4925);
DISPLAY INVISIBLE (-5200 4925);
FORCEPROP 1 LAST PATH I6
J 0
(-5200 4925);
DISPLAY 0.978723 (-5200 4925);
PAINT WHITE (-5200 4925);
DISPLAY INVISIBLE (-5200 4925);
FORCEPROP 0 LAST SEC 1
J 0
(-5200 4925);
DISPLAY 0.680851 (-5200 4925);
PAINT MONO (-5200 4925);
DISPLAY INVISIBLE (-5200 4925);
FORCEPROP 2 LAST BOM_COST SM_THERM
J 0
(-5200 4975);
DISPLAY 1.021277 (-5200 4975);
PAINT ORANGE (-5200 4975);
DISPLAY INVISIBLE (-5200 4975);
FORCEPROP 2 LAST SEC_TYPE 0402
J 0
(-5200 4975);
DISPLAY 1.021277 (-5200 4975);
PAINT ORANGE (-5200 4975);
DISPLAY INVISIBLE (-5200 4975);
FORCEADD OFFPAGE..3
(-5750 1450);
FORCEPROP 2 LAST $XR3 191 
J 0
(-5176 1450);
DISPLAY 0.638298 (-5176 1450);
PAINT MONO (-5176 1450);
FORCEPROP 2 LAST $XR2 184 
J 0
(-5296 1450);
DISPLAY 0.638298 (-5296 1450);
PAINT MONO (-5296 1450);
FORCEPROP 2 LAST $XR1 167 
J 0
(-5416 1450);
DISPLAY 0.638298 (-5416 1450);
PAINT MONO (-5416 1450);
FORCEPROP 2 LAST $XR0 164 
J 0
(-5536 1450);
DISPLAY 0.638298 (-5536 1450);
PAINT MONO (-5536 1450);
FORCEPROP 2 LAST CDS_LIB mstr_standard
J 0
(-5750 1450);
PAINT MONO (-5750 1450);
DISPLAY INVISIBLE (-5750 1450);
FORCEPROP 2 LAST PATH I60
J 0
(-5700 1525);
DISPLAY 1.021277 (-5700 1525);
PAINT ORANGE (-5700 1525);
DISPLAY INVISIBLE (-5700 1525);
FORCEPROP 1 LAST OFFPAGE TRUE
J 0
(-5425 1325);
DISPLAY 0.872340 (-5425 1325);
PAINT GREEN (-5425 1325);
DISPLAY INVISIBLE (-5425 1325);
FORCEPROP 1 LAST COMMENT_BODY TRUE
J 0
(-5800 1350);
DISPLAY 0.872340 (-5800 1350);
PAINT GREEN (-5800 1350);
DISPLAY INVISIBLE (-5800 1350);
FORCEADD OFFPAGE..6
(-7700 1450);
FORCEPROP 2 LAST $XR0 144 
J 0
(-7980 1450);
DISPLAY 0.638298 (-7980 1450);
PAINT MONO (-7980 1450);
FORCEPROP 2 LAST CDS_LIB mstr_standard
J 0
(-7700 1450);
PAINT MONO (-7700 1450);
DISPLAY INVISIBLE (-7700 1450);
FORCEPROP 2 LAST PATH I61
J 0
(-7650 1525);
DISPLAY 1.021277 (-7650 1525);
PAINT ORANGE (-7650 1525);
DISPLAY INVISIBLE (-7650 1525);
FORCEPROP 1 LAST OFFPAGE TRUE
J 0
(-7375 1325);
DISPLAY 0.872340 (-7375 1325);
PAINT GREEN (-7375 1325);
DISPLAY INVISIBLE (-7375 1325);
FORCEPROP 1 LAST COMMENT_BODY TRUE
J 0
(-7600 1375);
DISPLAY 0.872340 (-7600 1375);
PAINT GREEN (-7600 1375);
DISPLAY INVISIBLE (-7600 1375);
FORCEADD OFFPAGE..1
(-7700 1325);
FORCEPROP 2 LAST $XR0 144 
J 0
(-7982 1325);
DISPLAY 0.638298 (-7982 1325);
PAINT MONO (-7982 1325);
FORCEPROP 2 LAST CDS_LIB mstr_standard
J 0
(-7700 1325);
PAINT MONO (-7700 1325);
DISPLAY INVISIBLE (-7700 1325);
FORCEPROP 2 LAST PATH I62
J 0
(-7650 1400);
DISPLAY 1.021277 (-7650 1400);
PAINT ORANGE (-7650 1400);
DISPLAY INVISIBLE (-7650 1400);
FORCEPROP 1 LAST OFFPAGE TRUE
J 0
(-7375 1200);
DISPLAY 0.872340 (-7375 1200);
PAINT GREEN (-7375 1200);
DISPLAY INVISIBLE (-7375 1200);
FORCEPROP 1 LAST COMMENT_BODY TRUE
J 0
(-7575 1225);
DISPLAY 0.872340 (-7575 1225);
PAINT GREEN (-7575 1225);
DISPLAY INVISIBLE (-7575 1225);
FORCEADD OFFPAGE..2
(-5750 1325);
FORCEPROP 2 LAST $XR3 191 
J 0
(-5201 1325);
DISPLAY 0.638298 (-5201 1325);
PAINT MONO (-5201 1325);
FORCEPROP 2 LAST $XR2 184 
J 0
(-5321 1325);
DISPLAY 0.638298 (-5321 1325);
PAINT MONO (-5321 1325);
FORCEPROP 2 LAST $XR1 164 
J 0
(-5441 1325);
DISPLAY 0.638298 (-5441 1325);
PAINT MONO (-5441 1325);
FORCEPROP 2 LAST $XR0 167 
J 0
(-5561 1325);
DISPLAY 0.638298 (-5561 1325);
PAINT MONO (-5561 1325);
FORCEPROP 2 LAST CDS_LIB mstr_standard
J 0
(-5750 1325);
PAINT MONO (-5750 1325);
DISPLAY INVISIBLE (-5750 1325);
FORCEPROP 2 LAST PATH I63
J 0
(-5700 1400);
DISPLAY 1.021277 (-5700 1400);
PAINT ORANGE (-5700 1400);
DISPLAY INVISIBLE (-5700 1400);
FORCEPROP 1 LAST OFFPAGE TRUE
J 0
(-5425 1200);
DISPLAY 0.872340 (-5425 1200);
PAINT GREEN (-5425 1200);
DISPLAY INVISIBLE (-5425 1200);
FORCEPROP 1 LAST COMMENT_BODY TRUE
J 0
(-5795 1230);
DISPLAY 0.872340 (-5795 1230);
PAINT GREEN (-5795 1230);
DISPLAY INVISIBLE (-5795 1230);
FORCEADD CAP..1
(-4850 4625);
FORCEPROP 1 LAST PART_NUMBER A36095-025
R 1
J 0
(-4625 4525);
DISPLAY 0.617021 (-4625 4525);
PAINT BLUE (-4625 4525);
FORCEPROP 1 LAST VOLTAGE 50V
J 0
(-4800 4625);
DISPLAY 0.617021 (-4800 4625);
PAINT SKYBLUE (-4800 4625);
FORCEPROP 1 LAST LOCATION C1M4
J 0
(-4800 4725);
DISPLAY 0.617021 (-4800 4725);
PAINT AQUA (-4800 4725);
FORCEPROP 1 LASTPIN (-4850 4725) $PN 1
J 0
(-4840 4705);
DISPLAY 0.617021 (-4840 4705);
PAINT ORANGE (-4840 4705);
FORCEPROP 1 LAST VALUE 47.0PF
J 0
(-4800 4675);
DISPLAY 0.617021 (-4800 4675);
PAINT SKYBLUE (-4800 4675);
FORCEPROP 1 LAST TOLERANCE 5%
J 0
(-4800 4575);
DISPLAY 0.617021 (-4800 4575);
PAINT SKYBLUE (-4800 4575);
FORCEPROP 1 LASTPIN (-4850 4525) $PN 2
J 0
(-4840 4505);
DISPLAY 0.617021 (-4840 4505);
PAINT ORANGE (-4840 4505);
FORCEPROP 1 LAST MATERIAL EMPTY
J 0
(-4775 4500);
DISPLAY 0.617021 (-4775 4500);
PAINT RED (-4775 4500);
FORCEPROP 1 LAST PACK_TYPE 0402LF
J 0
(-4575 4725);
DISPLAY 0.617021 (-4575 4725);
PAINT SKYBLUE (-4575 4725);
FORCEPROP 2 LAST CDS_LIB mstr_discrete
J 0
(-4850 4625);
PAINT ORANGE (-4850 4625);
DISPLAY INVISIBLE (-4850 4625);
FORCEPROP 2 LAST CDS_LOCATION C1M4
J 0
(-4800 4725);
DISPLAY 0.617021 (-4800 4725);
PAINT AQUA (-4800 4725);
DISPLAY INVISIBLE (-4800 4725);
FORCEPROP 2 LAST ROOM TEMP_SENSORS
J 0
(-4800 4775);
DISPLAY 1.021277 (-4800 4775);
PAINT ORANGE (-4800 4775);
DISPLAY INVISIBLE (-4800 4775);
FORCEPROP 1 LAST PATH I7
J 0
(-4800 4775);
DISPLAY 0.978723 (-4800 4775);
PAINT WHITE (-4800 4775);
DISPLAY INVISIBLE (-4800 4775);
FORCEPROP 0 LAST SEC 1
J 0
(-4800 4775);
DISPLAY 0.680851 (-4800 4775);
PAINT MONO (-4800 4775);
DISPLAY INVISIBLE (-4800 4775);
FORCEPROP 2 LAST BOM_COST SM_THERM
J 0
(-4800 4825);
DISPLAY 1.021277 (-4800 4825);
PAINT ORANGE (-4800 4825);
DISPLAY INVISIBLE (-4800 4825);
FORCEPROP 2 LAST SEC_TYPE 0402LF
J 0
(-4800 4825);
DISPLAY 1.021277 (-4800 4825);
PAINT ORANGE (-4800 4825);
DISPLAY INVISIBLE (-4800 4825);
FORCEADD RES..2
(-3550 1975);
FORCEPROP 1 LAST LOCATION R8D28
J 0
(-3505 2100);
DISPLAY 0.617021 (-3505 2100);
PAINT AQUA (-3505 2100);
FORCEPROP 1 LASTPIN (-3550 2075) $PN 1
J 0
(-3545 2037);
DISPLAY 0.617021 (-3545 2037);
PAINT ORANGE (-3545 2037);
FORCEPROP 1 LAST PACK_TYPE 0402
J 0
(-3510 1800);
DISPLAY 0.617021 (-3510 1800);
PAINT SKYBLUE (-3510 1800);
FORCEPROP 1 LAST TOLERANCE 1%
J 0
(-3505 2000);
DISPLAY 0.617021 (-3505 2000);
PAINT SKYBLUE (-3505 2000);
FORCEPROP 1 LAST VALUE 1.00K
J 0
(-3505 2050);
DISPLAY 0.617021 (-3505 2050);
PAINT SKYBLUE (-3505 2050);
FORCEPROP 1 LAST WATTAGE 1/16W
J 0
(-3510 1950);
DISPLAY 0.617021 (-3510 1950);
PAINT SKYBLUE (-3510 1950);
FORCEPROP 1 LAST MATERIAL CHIP
J 0
(-3510 1900);
DISPLAY 0.617021 (-3510 1900);
PAINT SKYBLUE (-3510 1900);
FORCEPROP 1 LAST PART_NUMBER G21796-026
J 0
(-3510 1850);
DISPLAY 0.617021 (-3510 1850);
PAINT BLUE (-3510 1850);
FORCEPROP 1 LASTPIN (-3550 1875) $PN 2
J 0
(-3545 1885);
DISPLAY 0.617021 (-3545 1885);
PAINT ORANGE (-3545 1885);
FORCEPROP 2 LAST ROOM TEMP_SENSORS
J 0
(-3500 2150);
DISPLAY 1.021277 (-3500 2150);
PAINT ORANGE (-3500 2150);
DISPLAY INVISIBLE (-3500 2150);
FORCEPROP 1 LAST PATH I70
J 0
(-3500 2150);
DISPLAY 0.978723 (-3500 2150);
PAINT WHITE (-3500 2150);
DISPLAY INVISIBLE (-3500 2150);
FORCEPROP 2 LAST CDS_LOCATION R8D28
J 0
(-3505 2100);
DISPLAY 0.617021 (-3505 2100);
PAINT AQUA (-3505 2100);
DISPLAY INVISIBLE (-3505 2100);
FORCEPROP 0 LAST SEC 1
J 0
(-3500 2150);
DISPLAY 0.680851 (-3500 2150);
PAINT MONO (-3500 2150);
DISPLAY INVISIBLE (-3500 2150);
FORCEPROP 2 LAST BOM_COST SM_THERM
J 0
(-3500 2200);
DISPLAY 1.021277 (-3500 2200);
PAINT ORANGE (-3500 2200);
DISPLAY INVISIBLE (-3500 2200);
FORCEPROP 2 LAST SEC_TYPE 0402
J 0
(-3500 2200);
DISPLAY 1.021277 (-3500 2200);
PAINT ORANGE (-3500 2200);
DISPLAY INVISIBLE (-3500 2200);
FORCEPROP 2 LAST CDS_LIB mstr_discrete
J 0
(-3550 1975);
PAINT ORANGE (-3550 1975);
DISPLAY INVISIBLE (-3550 1975);
FORCEADD P3V3_STBY..1
(-3550 2200);
FORCEPROP 3 LASTPIN (-3550 2150) SIG_NAME P3V3_STBY\g
J 0
(-3540 2160);
DISPLAY 0.659574 (-3540 2160);
PAINT MONO (-3540 2160);
DISPLAY INVISIBLE (-3540 2160);
FORCEPROP 1 LAST SIZE 1B
J 0
(-3505 2222);
DISPLAY 0.340426 (-3505 2222);
PAINT GREEN (-3505 2222);
DISPLAY INVISIBLE (-3505 2222);
FORCEPROP 1 LAST PATH I71
J 0
(-3505 2202);
DISPLAY 0.340426 (-3505 2202);
PAINT GREEN (-3505 2202);
DISPLAY INVISIBLE (-3505 2202);
FORCEPROP 1 LAST VOLTAGE 3.3V
J 0
(-3595 2157);
DISPLAY 0.340426 (-3595 2157);
PAINT SKYBLUE (-3595 2157);
DISPLAY INVISIBLE (-3595 2157);
FORCEPROP 2 LAST CDS_LIB mstr_symbols
J 0
(-3550 2200);
PAINT MONO (-3550 2200);
DISPLAY INVISIBLE (-3550 2200);
FORCEPROP 1 LAST BODY_TYPE PLUMBING
J 0
(-3595 2157);
DISPLAY 0.340426 (-3595 2157);
PAINT GREEN (-3595 2157);
DISPLAY INVISIBLE (-3595 2157);
FORCEPROP 1 LAST HDL_POWER P3V3_STBY
J 0
(-3850 2075);
DISPLAY 0.872340 (-3850 2075);
PAINT ORANGE (-3850 2075);
DISPLAY INVISIBLE (-3850 2075);
FORCEADD P3V3_STBY..1
(-6375 4250);
FORCEPROP 3 LASTPIN (-6375 4200) SIG_NAME P3V3_STBY\g
J 0
(-6365 4210);
DISPLAY 0.659574 (-6365 4210);
PAINT MONO (-6365 4210);
DISPLAY INVISIBLE (-6365 4210);
FORCEPROP 1 LAST PATH I72
J 0
(-6330 4252);
DISPLAY 0.340426 (-6330 4252);
PAINT GREEN (-6330 4252);
DISPLAY INVISIBLE (-6330 4252);
FORCEPROP 1 LAST SIZE 1B
J 0
(-6330 4272);
DISPLAY 0.340426 (-6330 4272);
PAINT GREEN (-6330 4272);
DISPLAY INVISIBLE (-6330 4272);
FORCEPROP 2 LAST CDS_LIB mstr_symbols
J 0
(-6375 4250);
PAINT MONO (-6375 4250);
DISPLAY INVISIBLE (-6375 4250);
FORCEPROP 1 LAST VOLTAGE 3.3V
J 0
(-6420 4207);
DISPLAY 0.340426 (-6420 4207);
PAINT SKYBLUE (-6420 4207);
DISPLAY INVISIBLE (-6420 4207);
FORCEPROP 1 LAST BODY_TYPE PLUMBING
J 0
(-6420 4207);
DISPLAY 0.340426 (-6420 4207);
PAINT GREEN (-6420 4207);
DISPLAY INVISIBLE (-6420 4207);
FORCEPROP 1 LAST HDL_POWER P3V3_STBY
J 0
(-6675 4125);
DISPLAY 0.872340 (-6675 4125);
PAINT ORANGE (-6675 4125);
DISPLAY INVISIBLE (-6675 4125);
FORCEADD P3V3_STBY..1
(-1425 2400);
FORCEPROP 3 LASTPIN (-1425 2350) SIG_NAME P3V3_STBY\g
J 0
(-1415 2360);
DISPLAY 0.659574 (-1415 2360);
PAINT MONO (-1415 2360);
DISPLAY INVISIBLE (-1415 2360);
FORCEPROP 1 LAST PATH I73
J 0
(-1380 2402);
DISPLAY 0.340426 (-1380 2402);
PAINT GREEN (-1380 2402);
DISPLAY INVISIBLE (-1380 2402);
FORCEPROP 1 LAST VOLTAGE 3.3V
J 0
(-1470 2357);
DISPLAY 0.340426 (-1470 2357);
PAINT SKYBLUE (-1470 2357);
DISPLAY INVISIBLE (-1470 2357);
FORCEPROP 2 LAST CDS_LIB mstr_symbols
J 0
(-1425 2400);
PAINT ORANGE (-1425 2400);
DISPLAY INVISIBLE (-1425 2400);
FORCEPROP 1 LAST SIZE 1B
J 0
(-1380 2422);
DISPLAY 0.340426 (-1380 2422);
PAINT GREEN (-1380 2422);
DISPLAY INVISIBLE (-1380 2422);
FORCEPROP 1 LAST BODY_TYPE PLUMBING
J 0
(-1470 2357);
DISPLAY 0.340426 (-1470 2357);
PAINT GREEN (-1470 2357);
DISPLAY INVISIBLE (-1470 2357);
FORCEPROP 1 LAST HDL_POWER P3V3_STBY
J 0
(-1725 2275);
DISPLAY 0.872340 (-1725 2275);
PAINT ORANGE (-1725 2275);
DISPLAY INVISIBLE (-1725 2275);
FORCEADD RES..1
(-2650 4450);
FORCEPROP 1 LAST PACK_TYPE 0402
J 0
(-2775 4250);
DISPLAY 0.617021 (-2775 4250);
PAINT SKYBLUE (-2775 4250);
FORCEPROP 1 LAST MATERIAL CHIP
J 0
(-2650 4300);
DISPLAY 0.617021 (-2650 4300);
PAINT SKYBLUE (-2650 4300);
FORCEPROP 1 LAST PART_NUMBER G21796-173
J 0
(-2700 4550);
DISPLAY 0.617021 (-2700 4550);
PAINT BLUE (-2700 4550);
FORCEPROP 1 LAST LOCATION R1M8
J 0
(-2700 4500);
DISPLAY 0.617021 (-2700 4500);
PAINT AQUA (-2700 4500);
FORCEPROP 1 LAST VALUE 20.0
J 2
(-2675 4350);
DISPLAY 0.617021 (-2675 4350);
PAINT SKYBLUE (-2675 4350);
FORCEPROP 1 LAST WATTAGE 1/16W
J 2
(-2675 4300);
DISPLAY 0.617021 (-2675 4300);
PAINT SKYBLUE (-2675 4300);
FORCEPROP 1 LAST TOLERANCE 1%
J 0
(-2650 4350);
DISPLAY 0.617021 (-2650 4350);
PAINT SKYBLUE (-2650 4350);
FORCEPROP 1 LASTPIN (-2750 4450) $PN 1
J 0
(-2738 4462);
DISPLAY 0.617021 (-2738 4462);
PAINT ORANGE (-2738 4462);
FORCEPROP 1 LASTPIN (-2550 4450) $PN 2
J 0
(-2588 4462);
DISPLAY 0.617021 (-2588 4462);
PAINT ORANGE (-2588 4462);
FORCEPROP 2 LAST CDS_LIB mstr_discrete
J 0
(-2650 4450);
PAINT ORANGE (-2650 4450);
DISPLAY INVISIBLE (-2650 4450);
FORCEPROP 2 LAST CDS_LOCATION R1M8
J 0
(-2700 4500);
DISPLAY 0.617021 (-2700 4500);
PAINT AQUA (-2700 4500);
DISPLAY INVISIBLE (-2700 4500);
FORCEPROP 2 LAST ROOM TEMP_SENSORS
J 0
(-2700 4600);
DISPLAY 1.021277 (-2700 4600);
PAINT ORANGE (-2700 4600);
DISPLAY INVISIBLE (-2700 4600);
FORCEPROP 1 LAST PATH I74
J 0
(-2700 4600);
DISPLAY 0.978723 (-2700 4600);
PAINT WHITE (-2700 4600);
DISPLAY INVISIBLE (-2700 4600);
FORCEPROP 0 LAST SEC 1
J 0
(-2700 4600);
DISPLAY 0.680851 (-2700 4600);
PAINT MONO (-2700 4600);
DISPLAY INVISIBLE (-2700 4600);
FORCEPROP 2 LAST SEC_TYPE 0402
J 0
(-2700 4650);
DISPLAY 1.021277 (-2700 4650);
PAINT ORANGE (-2700 4650);
DISPLAY INVISIBLE (-2700 4650);
FORCEPROP 2 LAST BOM_COST SM_THERM
J 0
(-2700 4650);
DISPLAY 1.021277 (-2700 4650);
PAINT ORANGE (-2700 4650);
DISPLAY INVISIBLE (-2700 4650);
FORCEADD RES..1
(-2300 3000);
FORCEPROP 1 LAST PACK_TYPE 0402
J 0
(-2400 2800);
DISPLAY 0.617021 (-2400 2800);
PAINT SKYBLUE (-2400 2800);
FORCEPROP 1 LAST WATTAGE 1/16W
J 2
(-2325 2850);
DISPLAY 0.617021 (-2325 2850);
PAINT SKYBLUE (-2325 2850);
FORCEPROP 1 LASTPIN (-2400 3000) $PN 1
J 0
(-2388 3012);
DISPLAY 0.617021 (-2388 3012);
PAINT ORANGE (-2388 3012);
FORCEPROP 1 LAST VALUE 20.0
J 2
(-2325 2900);
DISPLAY 0.617021 (-2325 2900);
PAINT SKYBLUE (-2325 2900);
FORCEPROP 1 LASTPIN (-2200 3000) $PN 2
J 0
(-2238 3012);
DISPLAY 0.617021 (-2238 3012);
PAINT ORANGE (-2238 3012);
FORCEPROP 1 LAST TOLERANCE 1%
J 0
(-2300 2900);
DISPLAY 0.617021 (-2300 2900);
PAINT SKYBLUE (-2300 2900);
FORCEPROP 1 LAST LOCATION R9R7
J 0
(-2350 3050);
DISPLAY 0.617021 (-2350 3050);
PAINT AQUA (-2350 3050);
FORCEPROP 1 LAST PART_NUMBER G21796-173
J 0
(-2350 3100);
DISPLAY 0.617021 (-2350 3100);
PAINT BLUE (-2350 3100);
FORCEPROP 1 LAST MATERIAL CHIP
J 0
(-2300 2850);
DISPLAY 0.617021 (-2300 2850);
PAINT SKYBLUE (-2300 2850);
FORCEPROP 2 LAST CDS_LIB mstr_discrete
J 0
(-2300 3000);
PAINT ORANGE (-2300 3000);
DISPLAY INVISIBLE (-2300 3000);
FORCEPROP 2 LAST CDS_LOCATION R9R7
J 0
(-2350 3050);
DISPLAY 0.617021 (-2350 3050);
PAINT AQUA (-2350 3050);
DISPLAY INVISIBLE (-2350 3050);
FORCEPROP 2 LAST ROOM TEMP_SENSORS
J 0
(-2350 3150);
DISPLAY 1.021277 (-2350 3150);
PAINT ORANGE (-2350 3150);
DISPLAY INVISIBLE (-2350 3150);
FORCEPROP 1 LAST PATH I75
J 0
(-2350 3150);
DISPLAY 0.978723 (-2350 3150);
PAINT WHITE (-2350 3150);
DISPLAY INVISIBLE (-2350 3150);
FORCEPROP 0 LAST SEC 1
J 0
(-2350 3150);
DISPLAY 0.680851 (-2350 3150);
PAINT MONO (-2350 3150);
DISPLAY INVISIBLE (-2350 3150);
FORCEPROP 2 LAST BOM_COST SM_THERM
J 0
(-2350 3200);
DISPLAY 1.021277 (-2350 3200);
PAINT ORANGE (-2350 3200);
DISPLAY INVISIBLE (-2350 3200);
FORCEPROP 2 LAST SEC_TYPE 0402
J 0
(-2350 3200);
DISPLAY 1.021277 (-2350 3200);
PAINT ORANGE (-2350 3200);
DISPLAY INVISIBLE (-2350 3200);
FORCEADD RES..1
(-2625 3050);
FORCEPROP 1 LAST PART_NUMBER G21796-173
J 0
(-2675 3150);
DISPLAY 0.617021 (-2675 3150);
PAINT BLUE (-2675 3150);
FORCEPROP 1 LAST LOCATION R9R8
J 0
(-2675 3100);
DISPLAY 0.617021 (-2675 3100);
PAINT AQUA (-2675 3100);
FORCEPROP 1 LAST TOLERANCE 1%
J 0
(-2625 2950);
DISPLAY 0.617021 (-2625 2950);
PAINT SKYBLUE (-2625 2950);
FORCEPROP 1 LAST VALUE 20.0
J 2
(-2650 2950);
DISPLAY 0.617021 (-2650 2950);
PAINT SKYBLUE (-2650 2950);
FORCEPROP 1 LAST WATTAGE 1/16W
J 2
(-2650 2900);
DISPLAY 0.617021 (-2650 2900);
PAINT SKYBLUE (-2650 2900);
FORCEPROP 1 LASTPIN (-2725 3050) $PN 1
J 0
(-2713 3062);
DISPLAY 0.617021 (-2713 3062);
PAINT ORANGE (-2713 3062);
FORCEPROP 1 LASTPIN (-2525 3050) $PN 2
J 0
(-2563 3062);
DISPLAY 0.617021 (-2563 3062);
PAINT ORANGE (-2563 3062);
FORCEPROP 1 LAST PACK_TYPE 0402
J 0
(-2725 2850);
DISPLAY 0.617021 (-2725 2850);
PAINT SKYBLUE (-2725 2850);
FORCEPROP 1 LAST MATERIAL CHIP
J 0
(-2625 2900);
DISPLAY 0.617021 (-2625 2900);
PAINT SKYBLUE (-2625 2900);
FORCEPROP 2 LAST CDS_LIB mstr_discrete
J 0
(-2625 3050);
PAINT ORANGE (-2625 3050);
DISPLAY INVISIBLE (-2625 3050);
FORCEPROP 2 LAST ROOM TEMP_SENSORS
J 0
(-2675 3200);
DISPLAY 1.021277 (-2675 3200);
PAINT ORANGE (-2675 3200);
DISPLAY INVISIBLE (-2675 3200);
FORCEPROP 1 LAST PATH I76
J 0
(-2675 3200);
DISPLAY 0.978723 (-2675 3200);
PAINT WHITE (-2675 3200);
DISPLAY INVISIBLE (-2675 3200);
FORCEPROP 2 LAST CDS_LOCATION R9R8
J 0
(-2675 3100);
DISPLAY 0.617021 (-2675 3100);
PAINT AQUA (-2675 3100);
DISPLAY INVISIBLE (-2675 3100);
FORCEPROP 0 LAST SEC 1
J 0
(-2675 3200);
DISPLAY 0.680851 (-2675 3200);
PAINT MONO (-2675 3200);
DISPLAY INVISIBLE (-2675 3200);
FORCEPROP 2 LAST BOM_COST SM_THERM
J 0
(-2675 3250);
DISPLAY 1.021277 (-2675 3250);
PAINT ORANGE (-2675 3250);
DISPLAY INVISIBLE (-2675 3250);
FORCEPROP 2 LAST SEC_TYPE 0402
J 0
(-2675 3250);
DISPLAY 1.021277 (-2675 3250);
PAINT ORANGE (-2675 3250);
DISPLAY INVISIBLE (-2675 3250);
FORCEADD RES..1
(-6725 1325);
FORCEPROP 1 LAST PACK_TYPE 0402
J 0
(-6050 1275);
DISPLAY 0.617021 (-6050 1275);
PAINT SKYBLUE (-6050 1275);
FORCEPROP 1 LAST WATTAGE 1/16W
J 0
(-6225 1275);
DISPLAY 0.617021 (-6225 1275);
PAINT SKYBLUE (-6225 1275);
FORCEPROP 1 LAST TOLERANCE 1%
J 0
(-6650 1275);
DISPLAY 0.617021 (-6650 1275);
PAINT SKYBLUE (-6650 1275);
FORCEPROP 1 LAST PART_NUMBER G21796-173
J 0
(-6475 1275);
DISPLAY 0.617021 (-6475 1275);
PAINT BLUE (-6475 1275);
FORCEPROP 1 LAST LOCATION R9G14
J 0
(-7025 1275);
DISPLAY 0.617021 (-7025 1275);
PAINT AQUA (-7025 1275);
FORCEPROP 1 LAST MATERIAL CHIP
J 0
(-6575 1275);
DISPLAY 0.617021 (-6575 1275);
PAINT SKYBLUE (-6575 1275);
FORCEPROP 1 LAST VALUE 20.0
J 2
(-6775 1275);
DISPLAY 0.617021 (-6775 1275);
PAINT SKYBLUE (-6775 1275);
FORCEPROP 1 LASTPIN (-6825 1325) $PN 1
J 0
(-6813 1337);
DISPLAY 0.617021 (-6813 1337);
PAINT ORANGE (-6813 1337);
FORCEPROP 1 LASTPIN (-6625 1325) $PN 2
J 0
(-6663 1337);
DISPLAY 0.617021 (-6663 1337);
PAINT ORANGE (-6663 1337);
FORCEPROP 2 LAST CDS_LOCATION R9G14
J 0
(-6750 1375);
DISPLAY 0.617021 (-6750 1375);
PAINT AQUA (-6750 1375);
DISPLAY INVISIBLE (-6750 1375);
FORCEPROP 2 LAST CDS_LIB mstr_discrete
J 0
(-6725 1325);
PAINT MONO (-6725 1325);
DISPLAY INVISIBLE (-6725 1325);
FORCEPROP 1 LAST PATH I77
J 0
(-6775 1475);
DISPLAY 0.978723 (-6775 1475);
PAINT WHITE (-6775 1475);
DISPLAY INVISIBLE (-6775 1475);
FORCEPROP 2 LAST $SEC 1
J 0
(-6775 1525);
PAINT MONO (-6775 1525);
DISPLAY INVISIBLE (-6775 1525);
FORCEPROP 2 LAST CDS_SEC 1
J 0
(-6775 1525);
PAINT MONO (-6775 1525);
DISPLAY INVISIBLE (-6775 1525);
FORCEPROP 0 LAST ROOM SMBUS
J 0
(-6475 1375);
DISPLAY 1.021277 (-6475 1375);
PAINT ORANGE (-6475 1375);
DISPLAY INVISIBLE (-6475 1375);
FORCEPROP 0 LAST BOM_COST SM_CONTROLLER
J 0
(-6475 1475);
DISPLAY 1.021277 (-6475 1475);
PAINT ORANGE (-6475 1475);
DISPLAY INVISIBLE (-6475 1475);
FORCEPROP 0 LAST SKU B
J 0
(-6475 1375);
DISPLAY 1.021277 (-6475 1375);
PAINT ORANGE (-6475 1375);
DISPLAY INVISIBLE (-6475 1375);
FORCEADD RES..1
(-2950 4500);
FORCEPROP 1 LAST PACK_TYPE 0402
J 0
(-3075 4300);
DISPLAY 0.617021 (-3075 4300);
PAINT SKYBLUE (-3075 4300);
FORCEPROP 1 LAST WATTAGE 1/16W
J 2
(-2975 4350);
DISPLAY 0.617021 (-2975 4350);
PAINT SKYBLUE (-2975 4350);
FORCEPROP 1 LAST VALUE 20.0
J 2
(-2975 4400);
DISPLAY 0.617021 (-2975 4400);
PAINT SKYBLUE (-2975 4400);
FORCEPROP 1 LAST MATERIAL CHIP
J 0
(-2950 4350);
DISPLAY 0.617021 (-2950 4350);
PAINT SKYBLUE (-2950 4350);
FORCEPROP 1 LASTPIN (-3050 4500) $PN 1
J 0
(-3038 4512);
DISPLAY 0.617021 (-3038 4512);
PAINT ORANGE (-3038 4512);
FORCEPROP 1 LAST TOLERANCE 1%
J 0
(-2950 4400);
DISPLAY 0.617021 (-2950 4400);
PAINT SKYBLUE (-2950 4400);
FORCEPROP 1 LAST LOCATION R1M9
J 0
(-3000 4550);
DISPLAY 0.617021 (-3000 4550);
PAINT AQUA (-3000 4550);
FORCEPROP 1 LASTPIN (-2850 4500) $PN 2
J 0
(-2888 4512);
DISPLAY 0.617021 (-2888 4512);
PAINT ORANGE (-2888 4512);
FORCEPROP 1 LAST PART_NUMBER G21796-173
J 0
(-3000 4600);
DISPLAY 0.617021 (-3000 4600);
PAINT BLUE (-3000 4600);
FORCEPROP 2 LAST CDS_LOCATION R1M9
J 0
(-3000 4550);
DISPLAY 0.617021 (-3000 4550);
PAINT AQUA (-3000 4550);
DISPLAY INVISIBLE (-3000 4550);
FORCEPROP 2 LAST CDS_LIB mstr_discrete
J 0
(-2950 4500);
PAINT ORANGE (-2950 4500);
DISPLAY INVISIBLE (-2950 4500);
FORCEPROP 2 LAST ROOM TEMP_SENSORS
J 0
(-3000 4650);
DISPLAY 1.021277 (-3000 4650);
PAINT ORANGE (-3000 4650);
DISPLAY INVISIBLE (-3000 4650);
FORCEPROP 1 LAST PATH I8
J 0
(-3000 4650);
DISPLAY 0.978723 (-3000 4650);
PAINT WHITE (-3000 4650);
DISPLAY INVISIBLE (-3000 4650);
FORCEPROP 0 LAST SEC 1
J 0
(-3000 4650);
DISPLAY 0.680851 (-3000 4650);
PAINT MONO (-3000 4650);
DISPLAY INVISIBLE (-3000 4650);
FORCEPROP 2 LAST SEC_TYPE 0402
J 0
(-3000 4700);
DISPLAY 1.021277 (-3000 4700);
PAINT ORANGE (-3000 4700);
DISPLAY INVISIBLE (-3000 4700);
FORCEPROP 2 LAST BOM_COST SM_THERM
J 0
(-3000 4700);
DISPLAY 1.021277 (-3000 4700);
PAINT ORANGE (-3000 4700);
DISPLAY INVISIBLE (-3000 4700);
FORCEADD RES..2
(-6075 1950);
FORCEPROP 1 LAST MATERIAL CHIP
J 0
(-6035 1875);
DISPLAY 0.617021 (-6035 1875);
PAINT SKYBLUE (-6035 1875);
FORCEPROP 1 LAST WATTAGE 1/16W
J 0
(-6035 1925);
DISPLAY 0.617021 (-6035 1925);
PAINT SKYBLUE (-6035 1925);
FORCEPROP 1 LAST PACK_TYPE 0402
J 0
(-6035 1775);
DISPLAY 0.617021 (-6035 1775);
PAINT SKYBLUE (-6035 1775);
FORCEPROP 1 LASTPIN (-6075 1850) $PN 2
J 0
(-6070 1860);
DISPLAY 0.617021 (-6070 1860);
PAINT ORANGE (-6070 1860);
FORCEPROP 1 LASTPIN (-6075 2050) $PN 1
J 0
(-6070 2012);
DISPLAY 0.617021 (-6070 2012);
PAINT ORANGE (-6070 2012);
FORCEPROP 1 LAST TOLERANCE 1.0%
J 0
(-6030 1975);
DISPLAY 0.617021 (-6030 1975);
PAINT SKYBLUE (-6030 1975);
FORCEPROP 1 LAST VALUE 665
J 0
(-6030 2025);
DISPLAY 0.617021 (-6030 2025);
PAINT SKYBLUE (-6030 2025);
FORCEPROP 1 LAST LOCATION R2U38
J 0
(-6030 2075);
DISPLAY 0.617021 (-6030 2075);
PAINT AQUA (-6030 2075);
FORCEPROP 1 LAST PART_NUMBER G21796-235
J 0
(-6035 1825);
DISPLAY 0.617021 (-6035 1825);
PAINT BLUE (-6035 1825);
FORCEPROP 2 LAST CDS_LIB mstr_discrete
J 0
(-6075 1950);
PAINT ORANGE (-6075 1950);
DISPLAY INVISIBLE (-6075 1950);
FORCEPROP 2 LAST CDS_LOCATION R2U38
J 0
(-6030 2075);
DISPLAY 0.617021 (-6030 2075);
PAINT AQUA (-6030 2075);
DISPLAY INVISIBLE (-6030 2075);
FORCEPROP 0 LAST SEC 1
J 0
(-6025 2125);
DISPLAY 0.680851 (-6025 2125);
PAINT MONO (-6025 2125);
DISPLAY INVISIBLE (-6025 2125);
FORCEPROP 1 LAST PATH I80
J 0
(-6025 2125);
DISPLAY 0.978723 (-6025 2125);
PAINT WHITE (-6025 2125);
DISPLAY INVISIBLE (-6025 2125);
FORCEPROP 2 LAST SEC_TYPE 0402
J 0
(-6025 2175);
DISPLAY 1.021277 (-6025 2175);
PAINT ORANGE (-6025 2175);
DISPLAY INVISIBLE (-6025 2175);
FORCEPROP 0 LAST ROOM SMBUS
J 0
(-6025 2175);
DISPLAY 1.021277 (-6025 2175);
PAINT ORANGE (-6025 2175);
DISPLAY INVISIBLE (-6025 2175);
FORCEPROP 0 LAST BOM_COST SM_CONTROLLER
J 0
(-6025 2275);
DISPLAY 1.021277 (-6025 2275);
PAINT ORANGE (-6025 2275);
DISPLAY INVISIBLE (-6025 2275);
FORCEADD P3V3_STBY..1
(-6075 2200);
FORCEPROP 3 LASTPIN (-6075 2150) SIG_NAME P3V3_STBY\g
J 0
(-6065 2160);
DISPLAY 0.659574 (-6065 2160);
PAINT MONO (-6065 2160);
DISPLAY INVISIBLE (-6065 2160);
FORCEPROP 1 LAST VOLTAGE 3.3V
J 0
(-6120 2157);
DISPLAY 0.340426 (-6120 2157);
PAINT SKYBLUE (-6120 2157);
DISPLAY INVISIBLE (-6120 2157);
FORCEPROP 2 LAST CDS_LIB mstr_symbols
J 0
(-6075 2200);
PAINT ORANGE (-6075 2200);
DISPLAY INVISIBLE (-6075 2200);
FORCEPROP 1 LAST SIZE 1B
J 0
(-6030 2222);
DISPLAY 0.340426 (-6030 2222);
PAINT GREEN (-6030 2222);
DISPLAY INVISIBLE (-6030 2222);
FORCEPROP 1 LAST PATH I81
J 0
(-6030 2202);
DISPLAY 0.340426 (-6030 2202);
PAINT GREEN (-6030 2202);
DISPLAY INVISIBLE (-6030 2202);
FORCEPROP 1 LAST BODY_TYPE PLUMBING
J 0
(-6120 2157);
DISPLAY 0.340426 (-6120 2157);
PAINT GREEN (-6120 2157);
DISPLAY INVISIBLE (-6120 2157);
FORCEPROP 1 LAST HDL_POWER P3V3_STBY
J 0
(-6375 2075);
DISPLAY 0.872340 (-6375 2075);
PAINT ORANGE (-6375 2075);
DISPLAY INVISIBLE (-6375 2075);
FORCEADD P3V3_STBY..1
(-6425 2200);
FORCEPROP 3 LASTPIN (-6425 2150) SIG_NAME P3V3_STBY\g
J 0
(-6415 2160);
DISPLAY 0.659574 (-6415 2160);
PAINT MONO (-6415 2160);
DISPLAY INVISIBLE (-6415 2160);
FORCEPROP 1 LAST VOLTAGE 3.3V
J 0
(-6470 2157);
DISPLAY 0.340426 (-6470 2157);
PAINT SKYBLUE (-6470 2157);
DISPLAY INVISIBLE (-6470 2157);
FORCEPROP 2 LAST CDS_LIB mstr_symbols
J 0
(-6425 2200);
PAINT ORANGE (-6425 2200);
DISPLAY INVISIBLE (-6425 2200);
FORCEPROP 1 LAST SIZE 1B
J 0
(-6380 2222);
DISPLAY 0.340426 (-6380 2222);
PAINT GREEN (-6380 2222);
DISPLAY INVISIBLE (-6380 2222);
FORCEPROP 1 LAST PATH I82
J 0
(-6380 2202);
DISPLAY 0.340426 (-6380 2202);
PAINT GREEN (-6380 2202);
DISPLAY INVISIBLE (-6380 2202);
FORCEPROP 1 LAST BODY_TYPE PLUMBING
J 0
(-6470 2157);
DISPLAY 0.340426 (-6470 2157);
PAINT GREEN (-6470 2157);
DISPLAY INVISIBLE (-6470 2157);
FORCEPROP 1 LAST HDL_POWER P3V3_STBY
J 0
(-6725 2075);
DISPLAY 0.872340 (-6725 2075);
PAINT ORANGE (-6725 2075);
DISPLAY INVISIBLE (-6725 2075);
FORCEADD RES..2
(-6425 1950);
FORCEPROP 1 LAST PART_NUMBER G21796-235
J 0
(-6385 1825);
DISPLAY 0.617021 (-6385 1825);
PAINT BLUE (-6385 1825);
FORCEPROP 1 LAST WATTAGE 1/16W
J 0
(-6385 1925);
DISPLAY 0.617021 (-6385 1925);
PAINT SKYBLUE (-6385 1925);
FORCEPROP 1 LAST MATERIAL CHIP
J 0
(-6385 1875);
DISPLAY 0.617021 (-6385 1875);
PAINT SKYBLUE (-6385 1875);
FORCEPROP 1 LASTPIN (-6425 1850) $PN 2
J 0
(-6420 1860);
DISPLAY 0.617021 (-6420 1860);
PAINT ORANGE (-6420 1860);
FORCEPROP 1 LASTPIN (-6425 2050) $PN 1
J 0
(-6420 2012);
DISPLAY 0.617021 (-6420 2012);
PAINT ORANGE (-6420 2012);
FORCEPROP 1 LAST TOLERANCE 1.0%
J 0
(-6380 1975);
DISPLAY 0.617021 (-6380 1975);
PAINT SKYBLUE (-6380 1975);
FORCEPROP 1 LAST PACK_TYPE 0402
J 0
(-6385 1775);
DISPLAY 0.617021 (-6385 1775);
PAINT SKYBLUE (-6385 1775);
FORCEPROP 1 LAST VALUE 665
J 0
(-6380 2025);
DISPLAY 0.617021 (-6380 2025);
PAINT SKYBLUE (-6380 2025);
FORCEPROP 1 LAST LOCATION R2U39
J 0
(-6380 2075);
DISPLAY 0.617021 (-6380 2075);
PAINT AQUA (-6380 2075);
FORCEPROP 2 LAST CDS_LIB mstr_discrete
J 0
(-6425 1950);
PAINT ORANGE (-6425 1950);
DISPLAY INVISIBLE (-6425 1950);
FORCEPROP 0 LAST BOM_COST SM_CONTROLLER
J 0
(-6375 2275);
DISPLAY 1.021277 (-6375 2275);
PAINT ORANGE (-6375 2275);
DISPLAY INVISIBLE (-6375 2275);
FORCEPROP 2 LAST SEC_TYPE 0402
J 0
(-6375 2175);
DISPLAY 1.021277 (-6375 2175);
PAINT ORANGE (-6375 2175);
DISPLAY INVISIBLE (-6375 2175);
FORCEPROP 0 LAST SEC 1
J 0
(-6375 2125);
DISPLAY 0.680851 (-6375 2125);
PAINT MONO (-6375 2125);
DISPLAY INVISIBLE (-6375 2125);
FORCEPROP 2 LAST CDS_LOCATION R2U39
J 0
(-6380 2075);
DISPLAY 0.617021 (-6380 2075);
PAINT AQUA (-6380 2075);
DISPLAY INVISIBLE (-6380 2075);
FORCEPROP 1 LAST PATH I83
J 0
(-6375 2125);
DISPLAY 0.978723 (-6375 2125);
PAINT WHITE (-6375 2125);
DISPLAY INVISIBLE (-6375 2125);
FORCEPROP 0 LAST ROOM SMBUS
J 0
(-6375 2175);
DISPLAY 1.021277 (-6375 2175);
PAINT ORANGE (-6375 2175);
DISPLAY INVISIBLE (-6375 2175);
FORCEADD RES..1
(-4000 1550);
FORCEPROP 1 LAST PART_NUMBER G21796-173
J 0
(-4050 1650);
DISPLAY 0.617021 (-4050 1650);
PAINT BLUE (-4050 1650);
FORCEPROP 1 LASTPIN (-3900 1550) $PN 2
J 0
(-3938 1562);
DISPLAY 0.617021 (-3938 1562);
PAINT ORANGE (-3938 1562);
FORCEPROP 1 LASTPIN (-4100 1550) $PN 1
J 0
(-4088 1562);
DISPLAY 0.617021 (-4088 1562);
PAINT ORANGE (-4088 1562);
FORCEPROP 1 LAST PACK_TYPE 0402
J 0
(-4125 1350);
DISPLAY 0.617021 (-4125 1350);
PAINT SKYBLUE (-4125 1350);
FORCEPROP 1 LAST TOLERANCE 1%
J 0
(-4000 1450);
DISPLAY 0.617021 (-4000 1450);
PAINT SKYBLUE (-4000 1450);
FORCEPROP 1 LAST MATERIAL CHIP
J 0
(-4000 1400);
DISPLAY 0.617021 (-4000 1400);
PAINT SKYBLUE (-4000 1400);
FORCEPROP 1 LAST WATTAGE 1/16W
J 2
(-4025 1400);
DISPLAY 0.617021 (-4025 1400);
PAINT SKYBLUE (-4025 1400);
FORCEPROP 1 LAST VALUE 20.0
J 2
(-4025 1450);
DISPLAY 0.617021 (-4025 1450);
PAINT SKYBLUE (-4025 1450);
FORCEPROP 1 LAST LOCATION R8D24
J 0
(-4050 1600);
DISPLAY 0.617021 (-4050 1600);
PAINT AQUA (-4050 1600);
FORCEPROP 0 LAST BOM_COST SM_THERM
J 0
(-4050 1850);
DISPLAY 1.021277 (-4050 1850);
PAINT ORANGE (-4050 1850);
DISPLAY INVISIBLE (-4050 1850);
FORCEPROP 2 LAST SEC_TYPE 0402
J 0
(-4050 1750);
DISPLAY 1.021277 (-4050 1750);
PAINT ORANGE (-4050 1750);
DISPLAY INVISIBLE (-4050 1750);
FORCEPROP 0 LAST ROOM TEMP_SENSORS
J 0
(-4050 1750);
DISPLAY 1.021277 (-4050 1750);
PAINT ORANGE (-4050 1750);
DISPLAY INVISIBLE (-4050 1750);
FORCEPROP 2 LAST CDS_LIB mstr_discrete
J 0
(-4000 1550);
PAINT ORANGE (-4000 1550);
DISPLAY INVISIBLE (-4000 1550);
FORCEPROP 0 LAST SEC 1
J 0
(-4050 1700);
DISPLAY 0.680851 (-4050 1700);
PAINT MONO (-4050 1700);
DISPLAY INVISIBLE (-4050 1700);
FORCEPROP 2 LAST CDS_LOCATION R8D24
J 0
(-4050 1600);
DISPLAY 0.617021 (-4050 1600);
PAINT AQUA (-4050 1600);
DISPLAY INVISIBLE (-4050 1600);
FORCEPROP 1 LAST PATH I84
J 0
(-4050 1700);
DISPLAY 0.978723 (-4050 1700);
PAINT WHITE (-4050 1700);
DISPLAY INVISIBLE (-4050 1700);
FORCEADD RES..1
(-1475 1550);
FORCEPROP 1 LAST PACK_TYPE 0402
J 0
(-1325 1400);
DISPLAY 0.617021 (-1325 1400);
PAINT SKYBLUE (-1325 1400);
FORCEPROP 1 LAST MATERIAL CHIP
J 0
(-1475 1400);
DISPLAY 0.617021 (-1475 1400);
PAINT SKYBLUE (-1475 1400);
FORCEPROP 1 LAST TOLERANCE 1%
J 0
(-1475 1450);
DISPLAY 0.617021 (-1475 1450);
PAINT SKYBLUE (-1475 1450);
FORCEPROP 1 LAST VALUE 20.0
J 2
(-1500 1450);
DISPLAY 0.617021 (-1500 1450);
PAINT SKYBLUE (-1500 1450);
FORCEPROP 1 LASTPIN (-1575 1550) $PN 1
J 0
(-1563 1562);
DISPLAY 0.787234 (-1563 1562);
PAINT ORANGE (-1563 1562);
FORCEPROP 1 LAST WATTAGE 1/16W
J 2
(-1500 1400);
DISPLAY 0.617021 (-1500 1400);
PAINT SKYBLUE (-1500 1400);
FORCEPROP 1 LASTPIN (-1375 1550) $PN 2
J 0
(-1413 1562);
DISPLAY 0.787234 (-1413 1562);
PAINT ORANGE (-1413 1562);
FORCEPROP 1 LAST LOCATION R8D23
J 0
(-1525 1600);
DISPLAY 0.617021 (-1525 1600);
PAINT AQUA (-1525 1600);
FORCEPROP 1 LAST PART_NUMBER G21796-173
J 0
(-1525 1650);
DISPLAY 0.617021 (-1525 1650);
PAINT BLUE (-1525 1650);
FORCEPROP 0 LAST ROOM TEMP_SENSORS
J 0
(-1525 1750);
DISPLAY 1.021277 (-1525 1750);
PAINT ORANGE (-1525 1750);
DISPLAY INVISIBLE (-1525 1750);
FORCEPROP 1 LAST PATH I85
J 0
(-1525 1700);
DISPLAY 0.978723 (-1525 1700);
PAINT WHITE (-1525 1700);
DISPLAY INVISIBLE (-1525 1700);
FORCEPROP 2 LAST CDS_LOCATION R8D23
J 0
(-1525 1600);
DISPLAY 0.617021 (-1525 1600);
PAINT AQUA (-1525 1600);
DISPLAY INVISIBLE (-1525 1600);
FORCEPROP 0 LAST BOM_COST SM_THERM
J 0
(-1525 1850);
DISPLAY 1.021277 (-1525 1850);
PAINT ORANGE (-1525 1850);
DISPLAY INVISIBLE (-1525 1850);
FORCEPROP 2 LAST CDS_LIB mstr_discrete
J 0
(-1475 1550);
PAINT ORANGE (-1475 1550);
DISPLAY INVISIBLE (-1475 1550);
FORCEPROP 2 LAST SEC 1
J 0
(-1525 1750);
PAINT MONO (-1525 1750);
DISPLAY INVISIBLE (-1525 1750);
FORCEPROP 2 LAST SEC_TYPE 0402
J 0
(-1525 1750);
DISPLAY 1.021277 (-1525 1750);
PAINT ORANGE (-1525 1750);
DISPLAY INVISIBLE (-1525 1750);
FORCEADD OFFPAGE..1
(-4900 1550);
FORCEPROP 2 LAST $XR3 191 
J 0
(-5542 1550);
DISPLAY 0.638298 (-5542 1550);
PAINT MONO (-5542 1550);
FORCEPROP 2 LAST $XR2 184 
J 0
(-5422 1550);
DISPLAY 0.638298 (-5422 1550);
PAINT MONO (-5422 1550);
FORCEPROP 2 LAST $XR1 164 
J 0
(-5302 1550);
DISPLAY 0.638298 (-5302 1550);
PAINT MONO (-5302 1550);
FORCEPROP 2 LAST $XR0 167 
J 0
(-5182 1550);
DISPLAY 0.638298 (-5182 1550);
PAINT MONO (-5182 1550);
FORCEPROP 2 LAST CDS_LIB mstr_standard
J 0
(-4900 1550);
PAINT ORANGE (-4900 1550);
DISPLAY INVISIBLE (-4900 1550);
FORCEPROP 2 LAST PATH I86
J 0
(-4850 1625);
DISPLAY 1.021277 (-4850 1625);
PAINT ORANGE (-4850 1625);
DISPLAY INVISIBLE (-4850 1625);
FORCEPROP 1 LAST OFFPAGE TRUE
J 0
(-4575 1425);
DISPLAY 0.872340 (-4575 1425);
PAINT GREEN (-4575 1425);
DISPLAY INVISIBLE (-4575 1425);
FORCEPROP 1 LAST COMMENT_BODY TRUE
J 0
(-4775 1450);
DISPLAY 0.872340 (-4775 1450);
PAINT GREEN (-4775 1450);
DISPLAY INVISIBLE (-4775 1450);
FORCEADD OFFPAGE..3
(-550 1550);
FORCEPROP 2 LAST $XR3 191 
J 0
(-336 1478);
DISPLAY 0.638298 (-336 1478);
PAINT MONO (-336 1478);
FORCEPROP 2 LAST $XR2 184 
J 0
(-336 1586);
DISPLAY 0.638298 (-336 1586);
PAINT MONO (-336 1586);
FORCEPROP 2 LAST $XR1 167 
J 0
(-336 1514);
DISPLAY 0.638298 (-336 1514);
PAINT MONO (-336 1514);
FORCEPROP 2 LAST $XR0 164 
J 0
(-336 1550);
DISPLAY 0.638298 (-336 1550);
PAINT MONO (-336 1550);
FORCEPROP 2 LAST CDS_LIB mstr_standard
J 0
(-550 1550);
PAINT ORANGE (-550 1550);
DISPLAY INVISIBLE (-550 1550);
FORCEPROP 2 LAST PATH I87
J 0
(-500 1625);
DISPLAY 1.021277 (-500 1625);
PAINT ORANGE (-500 1625);
DISPLAY INVISIBLE (-500 1625);
FORCEPROP 1 LAST OFFPAGE TRUE
J 0
(-225 1425);
DISPLAY 0.872340 (-225 1425);
PAINT GREEN (-225 1425);
DISPLAY INVISIBLE (-225 1425);
FORCEPROP 1 LAST COMMENT_BODY TRUE
J 0
(-600 1450);
DISPLAY 0.872340 (-600 1450);
PAINT GREEN (-600 1450);
DISPLAY INVISIBLE (-600 1450);
FORCEADD 2SB2907A-B0-00001-GP..1
R 4
(-5925 4600);
FORCEPROP 1 LAST VALUE 2SB2907A-B0-00001-GP
J 0
(-5875 4650);
DISPLAY 0.617021 (-5875 4650);
PAINT GREEN (-5875 4650);
FORCEPROP 2 LASTPIN (-5975 4700) $PN E
J 2
(-5915 4710);
DISPLAY 0.808511 (-5915 4710);
PAINT ORANGE (-5915 4710);
FORCEPROP 2 LASTPIN (-5825 4600) $PN B
J 2
(-5840 4615);
DISPLAY 0.808511 (-5840 4615);
PAINT ORANGE (-5840 4615);
FORCEPROP 2 LASTPIN (-5975 4500) $PN C
J 0
(-5965 4490);
DISPLAY 0.808511 (-5965 4490);
PAINT ORANGE (-5965 4490);
FORCEPROP 1 LAST LOCATION Q9B1
J 0
(-5875 4700);
DISPLAY 0.617021 (-5875 4700);
PAINT GREEN (-5875 4700);
FORCEPROP 1 LAST PATH I93
R 2
J 0
(-5925 4527);
DISPLAY 0.617021 (-5925 4527);
PAINT GREEN (-5925 4527);
DISPLAY INVISIBLE (-5925 4527);
FORCEPROP 1 LAST PACK_TYPE DISCRET-GB1
R 2
J 0
(-5925 4600);
DISPLAY 0.617021 (-5925 4600);
PAINT GREEN (-5925 4600);
DISPLAY INVISIBLE (-5925 4600);
FORCEPROP 2 LAST SEC 1
R 2
J 0
(-6000 4475);
DISPLAY 0.680851 (-6000 4475);
PAINT MONO (-6000 4475);
DISPLAY INVISIBLE (-6000 4475);
FORCEPROP 2 LAST SEC_TYPE DISCRET-GB1
R 2
J 0
(-6000 4475);
DISPLAY 1.021277 (-6000 4475);
PAINT ORANGE (-6000 4475);
DISPLAY INVISIBLE (-6000 4475);
FORCEPROP 1 LAST PART_NUMBER 006.02907.001A
R 2
J 0
(-5925 4672);
DISPLAY 0.617021 (-5925 4672);
PAINT GREEN (-5925 4672);
DISPLAY INVISIBLE (-5925 4672);
FORCEPROP 2 LAST CDS_LIB w_hdl
R 2
J 0
(-5925 4600);
DISPLAY INVISIBLE (-5925 4600);
FORCEPROP 1 LAST CDS_LMAN_SYM_OUTLINE -50,50,50,-50
R 2
J 0
(-5925 4600);
DISPLAY 0.468085 (-5925 4600);
PAINT GREEN (-5925 4600);
DISPLAY INVISIBLE (-5925 4600);
FORCEADD 2SB2907A-B0-00001-GP..1
R 4
(-5700 3150);
FORCEPROP 2 LASTPIN (-5600 3150) $PN B
J 2
(-5615 3165);
DISPLAY 0.808511 (-5615 3165);
PAINT ORANGE (-5615 3165);
FORCEPROP 1 LAST LOCATION Q1E1
J 0
(-5650 3250);
DISPLAY 0.617021 (-5650 3250);
PAINT GREEN (-5650 3250);
FORCEPROP 2 LASTPIN (-5750 3250) $PN E
J 2
(-5690 3260);
DISPLAY 0.808511 (-5690 3260);
PAINT ORANGE (-5690 3260);
FORCEPROP 2 LASTPIN (-5750 3050) $PN C
J 0
(-5740 3040);
DISPLAY 0.808511 (-5740 3040);
PAINT ORANGE (-5740 3040);
FORCEPROP 1 LAST VALUE 2SB2907A-B0-00001-GP
J 0
(-5650 3200);
DISPLAY 0.617021 (-5650 3200);
PAINT GREEN (-5650 3200);
FORCEPROP 1 LAST PACK_TYPE DISCRET-GB1
R 2
J 0
(-5700 3150);
DISPLAY 0.617021 (-5700 3150);
PAINT GREEN (-5700 3150);
DISPLAY INVISIBLE (-5700 3150);
FORCEPROP 2 LAST SEC 1
R 2
J 0
(-5775 3025);
DISPLAY 0.680851 (-5775 3025);
PAINT MONO (-5775 3025);
DISPLAY INVISIBLE (-5775 3025);
FORCEPROP 2 LAST SEC_TYPE DISCRET-GB1
R 2
J 0
(-5775 3025);
DISPLAY 1.021277 (-5775 3025);
PAINT ORANGE (-5775 3025);
DISPLAY INVISIBLE (-5775 3025);
FORCEPROP 1 LAST PART_NUMBER 006.02907.001A
R 2
J 0
(-5700 3222);
DISPLAY 0.617021 (-5700 3222);
PAINT GREEN (-5700 3222);
DISPLAY INVISIBLE (-5700 3222);
FORCEPROP 2 LAST CDS_LIB w_hdl
R 2
J 0
(-5700 3150);
DISPLAY INVISIBLE (-5700 3150);
FORCEPROP 1 LAST CDS_LMAN_SYM_OUTLINE -50,50,50,-50
R 2
J 0
(-5700 3150);
DISPLAY 0.468085 (-5700 3150);
PAINT GREEN (-5700 3150);
DISPLAY INVISIBLE (-5700 3150);
FORCEPROP 1 LAST PATH I94
R 2
J 0
(-5700 3077);
DISPLAY 0.617021 (-5700 3077);
PAINT GREEN (-5700 3077);
DISPLAY INVISIBLE (-5700 3077);
FORCEADD DNS..2
(-4845 4620);
PAINT RED (-4845 4620);
FORCEPROP 2 LAST CDS_LIB mstr_misc
J 0
(-4845 4620);
PAINT ORANGE (-4845 4620);
DISPLAY INVISIBLE (-4845 4620);
FORCEPROP 1 LAST COMMENT_BODY TRUE
R 1
J 0
(-4770 4395);
DISPLAY 0.872340 (-4770 4395);
PAINT GREEN (-4770 4395);
DISPLAY INVISIBLE (-4770 4395);
FORCEADD DESIGN_NOTE..1
(-6075 2600);
FORCEPROP 2 LAST CDS_LIB mstr_symbols
J 0
(-6075 2600);
PAINT ORANGE (-6075 2600);
DISPLAY INVISIBLE (-6075 2600);
FORCEPROP 1 LAST COMMENT_BODY TRUE
J 0
(-6050 2700);
DISPLAY 0.978723 (-6050 2700);
PAINT ORANGE (-6050 2700);
DISPLAY INVISIBLE (-6050 2700);
FORCEADD CAD_NOTE..1
(-825 2250);
FORCEPROP 0 LAST L2 TO AT24C64
J 0
(-975 2050);
DISPLAY 1.021277 (-975 2050);
PAINT ORANGE (-975 2050);
FORCEPROP 0 LAST L1 PLACE CAP CLOSE
J 0
(-975 2125);
DISPLAY 1.021277 (-975 2125);
PAINT ORANGE (-975 2125);
FORCEPROP 2 LAST CDS_LIB mstr_symbols
J 0
(-825 2250);
PAINT ORANGE (-825 2250);
DISPLAY INVISIBLE (-825 2250);
FORCEPROP 1 LAST COMMENT_BODY TRUE
J 0
(-800 2350);
DISPLAY 0.978723 (-800 2350);
PAINT ORANGE (-800 2350);
DISPLAY INVISIBLE (-800 2350);
FORCEADD CAD_NOTE..1
(-4425 1025);
FORCEPROP 0 LAST L1 PLACE SERIES RESISTORS ON SMB_SENSOR_STBY_LVC3_SDA/SCL NETS CLOSE TO AT24C64
J 0
(-4575 875);
DISPLAY 0.808511 (-4575 875);
PAINT ORANGE (-4575 875);
FORCEPROP 2 LAST CDS_LIB mstr_symbols
J 0
(-4425 1025);
PAINT ORANGE (-4425 1025);
DISPLAY INVISIBLE (-4425 1025);
FORCEPROP 1 LAST COMMENT_BODY TRUE
J 0
(-4400 1125);
DISPLAY 0.978723 (-4400 1125);
PAINT ORANGE (-4400 1125);
DISPLAY INVISIBLE (-4400 1125);
FORCEADD DESIGN_NOTE..1
(-2100 1300);
FORCEPROP 2 LAST CDS_LIB mstr_symbols
J 0
(-2100 1300);
PAINT ORANGE (-2100 1300);
DISPLAY INVISIBLE (-2100 1300);
FORCEPROP 1 LAST COMMENT_BODY TRUE
J 0
(-2075 1400);
DISPLAY 0.978723 (-2075 1400);
PAINT ORANGE (-2075 1400);
DISPLAY INVISIBLE (-2075 1400);
FORCEADD CAD_NOTE..1
(-7175 800);
FORCEPROP 0 LAST L1 PLEASE CONTACT DE WHEN CONNECTING THESE RESISTORS
J 0
(-7325 675);
DISPLAY 0.808511 (-7325 675);
PAINT ORANGE (-7325 675);
FORCEPROP 2 LAST CDS_LIB mstr_symbols
J 0
(-7175 800);
PAINT MONO (-7175 800);
DISPLAY INVISIBLE (-7175 800);
FORCEPROP 1 LAST COMMENT_BODY TRUE
J 0
(-7150 900);
DISPLAY 0.978723 (-7150 900);
PAINT ORANGE (-7150 900);
DISPLAY INVISIBLE (-7150 900);
FORCEADD DNS..2
(-4670 3170);
PAINT RED (-4670 3170);
FORCEPROP 2 LAST CDS_LIB mstr_misc
J 0
(-4670 3170);
PAINT ORANGE (-4670 3170);
DISPLAY INVISIBLE (-4670 3170);
FORCEPROP 1 LAST COMMENT_BODY TRUE
R 1
J 0
(-4595 2945);
DISPLAY 0.872340 (-4595 2945);
PAINT GREEN (-4595 2945);
DISPLAY INVISIBLE (-4595 2945);
FORCEADD CAD_NOTE..1
(-3275 5125);
FORCEPROP 0 LAST L1 PLACE UPPER TMP421 ON EDGE OF BOARD NEAR RJ 45
J 0
(-3425 5000);
DISPLAY 1.021277 (-3425 5000);
PAINT ORANGE (-3425 5000);
FORCEPROP 2 LAST CDS_LIB mstr_symbols
J 0
(-3275 5125);
PAINT ORANGE (-3275 5125);
DISPLAY INVISIBLE (-3275 5125);
FORCEPROP 1 LAST COMMENT_BODY TRUE
J 0
(-3250 5225);
DISPLAY 0.978723 (-3250 5225);
PAINT ORANGE (-3250 5225);
DISPLAY INVISIBLE (-3250 5225);
FORCEADD INTEL_CORP_BPAGE..1
(-225 325);
FORCEPROP 1 LAST CDS_CON_LAST_MODIFIED Fri Jun 16 17:49:02 2017
J 0
(-1650 650);
DISPLAY 1.361702 (-1650 650);
PAINT GREEN (-1650 650);
DISPLAY INVISIBLE (-1650 650);
FORCEPROP 1 LAST CUSTOM_TXT_CDS <CURRENT_DESIGN_SHEET> OF <TOTAL_DESIGN_SHEETS>
J 0
(-725 350);
PAINT ORANGE (-725 350);
FORCEPROP 2 LAST CUSTOM_TXT_CDS <XR_PAGE_TITLE>
J 0
(-8115 5575);
DISPLAY 0.638298 (-8115 5575);
PAINT PINK (-8115 5575);
DISPLAY INVISIBLE (-8115 5575);
FORCEPROP 2 LAST CUSTOM_TXT_CDS <CON_LAST_MODIFIED>
J 0
(-4225 400);
DISPLAY 1.361702 (-4225 400);
PAINT ORANGE (-4225 400);
FORCEPROP 1 LAST SCH_TITLE TEMPERATURE SENSORS AND FRU
J 0
(-8175 375);
DISPLAY 1.212766 (-8175 375);
PAINT ORANGE (-8175 375);
FORCEPROP 2 LAST PAGE_BORDER TRUE
J 0
(-8115 5575);
DISPLAY 0.851064 (-8115 5575);
PAINT PINK (-8115 5575);
DISPLAY INVISIBLE (-8115 5575);
FORCEPROP 2 LAST CDS_LIB mstr_symbols
J 0
(-225 325);
DISPLAY 1.361702 (-225 325);
PAINT ORANGE (-225 325);
DISPLAY INVISIBLE (-225 325);
FORCEPROP 1 LAST COMMENT_BODY TRUE
J 0
(-213 337);
DISPLAY 0.617021 (-213 337);
PAINT GREEN (-213 337);
DISPLAY INVISIBLE (-213 337);
FORCEPROP 2 LAST CDS_XR_PAGE_TITLE CR-167 : @BASEBOARD_FAB2_LIB.BASEBOARD_FAB2(SCH_1):PAGE167
J 0
(-8115 5575);
DISPLAY 0.638298 (-8115 5575);
PAINT PINK (-8115 5575);
DISPLAY INVISIBLE (-8115 5575);
FORCEADD DESIGN_NOTE..1
(-6575 4050);
FORCEPROP 2 LAST CDS_LIB mstr_symbols
J 0
(-6575 4050);
PAINT ORANGE (-6575 4050);
DISPLAY INVISIBLE (-6575 4050);
FORCEPROP 1 LAST COMMENT_BODY TRUE
J 0
(-6550 4150);
DISPLAY 0.978723 (-6550 4150);
PAINT ORANGE (-6550 4150);
DISPLAY INVISIBLE (-6550 4150);
FORCEADD CAD_NOTE..1
(-3275 3575);
FORCEPROP 0 LAST L1 PLACE LOWER TMP421 ON EDGE OF BOARD NEAR AIRMAX CONNECTORS
J 0
(-3425 3450);
DISPLAY 0.808511 (-3425 3450);
PAINT ORANGE (-3425 3450);
FORCEPROP 2 LAST CDS_LIB mstr_symbols
J 0
(-3275 3575);
PAINT ORANGE (-3275 3575);
DISPLAY INVISIBLE (-3275 3575);
FORCEPROP 1 LAST COMMENT_BODY TRUE
J 0
(-3250 3675);
DISPLAY 0.978723 (-3250 3675);
PAINT ORANGE (-3250 3675);
DISPLAY INVISIBLE (-3250 3675);
WIRE 16 -1 (-4775 3900)(-4775 3975);
WIRE 16 -1 (-4350 5100)(-4350 4600);
WIRE 16 -1 (-4350 4600)(-4300 4600);
WIRE 16 -1 (-3400 3900)(-3400 4250);
WIRE 16 -1 (-3400 4250)(-3700 4250);
WIRE 16 -1 (-3225 2450)(-3225 2800);
WIRE 16 -1 (-3225 2800)(-3525 2800);
WIRE 16 -1 (-4175 3650)(-4175 3150);
WIRE 16 -1 (-4175 3150)(-4125 3150);
WIRE 16 -1 (-6400 3025)(-6400 2900);
WIRE 16 -1 (-6400 2900)(-6400 2850);
WIRE 16 -1 (-6400 2900)(-4750 2900);
WIRE 16 -1 (-6400 2850)(-5150 2850);
WIRE 16 -1 (-7700 3400)(-7700 3575);
WIRE 16 -1 (-1425 2050)(-1425 1875);
WIRE 16 -1 (-7700 4150)(-7700 4250);
WIRE 16 -1 (-3500 1100)(-3500 1200);
WIRE 16 -1 (-3075 1100)(-3075 1650);
WIRE 16 -1 (-3075 1700)(-3075 1650);
WIRE 16 -1 (-3075 1650)(-3000 1650);
WIRE 16 -1 (-3075 1700)(-3000 1700);
WIRE 16 -1 (-7700 4600)(-7700 4450);
WIRE 16 -1 (-7700 3900)(-7700 3775);
WIRE 16 -1 (-3550 2150)(-3550 2075);
WIRE 16 -1 (-6375 4200)(-6375 4150);
WIRE 16 -1 (-6375 4150)(-5575 4150);
WIRE 16 -1 (-1425 2350)(-1425 2250);
WIRE 16 -1 (-6075 2050)(-6075 2150);
WIRE 16 -1 (-6425 2050)(-6425 2150);
WIRE 16 -1 (-5975 4500)(-5975 4450);
WIRE 16 -1 (-5325 4450)(-5975 4450);
FORCEPROP 2 LAST SIG_NAME ISENSE_TMP421_1_BC
J 0
(-5960 4460);
DISPLAY 0.617021 (-5960 4460);
PAINT ORANGE (-5960 4460);
FORCEPROP 2 LASTPROP $XRERR UNIQUE?
J 0
(-6200 4460);
DISPLAY 0.638298 (-6200 4460);
PAINT MONO (-6200 4460);
DISPLAY INVISIBLE (-6200 4460);
WIRE 16 -1 (-5250 4450)(-5325 4450);
WIRE 16 -1 (-5325 4600)(-5325 4450);
WIRE 16 -1 (-5825 4600)(-5325 4600);
WIRE 3 682 (-6350 4400)(-6450 4400);
WIRE 3 682 (-6350 4400)(-6350 4500);
WIRE 3 682 (-6450 4400)(-6450 4500);
WIRE 3 682 (-6400 4500)(-6450 4500);
WIRE 3 682 (-6350 4500)(-6400 4500);
WIRE 3 682 (-6400 4500)(-6400 4850);
WIRE 3 682 (-6050 4850)(-6050 4400);
WIRE 3 682 (-5450 4850)(-6050 4850);
WIRE 3 682 (-6050 4400)(-5450 4400);
WIRE 3 682 (-5450 4400)(-5450 4850);
WIRE 3 682 (-7300 4825)(-7300 4400);
WIRE 3 682 (-6950 4825)(-7300 4825);
WIRE 3 682 (-7300 4400)(-6950 4400);
WIRE 3 682 (-6950 4400)(-6950 4825);
WIRE 16 -1 (-5975 4700)(-5975 4775);
WIRE 16 -1 (-5975 4775)(-5250 4775);
FORCEPROP 2 LAST SIG_NAME ISENSE_TMP421_1_E
J 0
(-5960 4785);
DISPLAY 0.617021 (-5960 4785);
PAINT ORANGE (-5960 4785);
FORCEPROP 2 LASTPROP $XRERR UNIQUE?
J 0
(-6200 4785);
DISPLAY 0.638298 (-6200 4785);
PAINT MONO (-6200 4785);
DISPLAY INVISIBLE (-6200 4785);
WIRE 16 -1 (-4850 4350)(-4300 4350);
FORCEPROP 2 LAST SIG_NAME PU_TMP421_1_A1
J 0
(-4800 4360);
DISPLAY 0.617021 (-4800 4360);
PAINT ORANGE (-4800 4360);
FORCEPROP 2 LASTPROP $XRERR UNIQUE?
J 0
(-5040 4360);
DISPLAY 0.638298 (-5040 4360);
PAINT MONO (-5040 4360);
DISPLAY INVISIBLE (-5040 4360);
WIRE 16 -1 (-5375 4150)(-4850 4150);
WIRE 16 -1 (-4850 4150)(-4850 4350);
WIRE 16 -1 (-3550 1875)(-3550 1750);
WIRE 16 -1 (-3550 1750)(-3000 1750);
FORCEPROP 2 LAST SIG_NAME PU_AT24C64_A2
J 0
(-3535 1760);
DISPLAY 0.617021 (-3535 1760);
PAINT ORANGE (-3535 1760);
FORCEPROP 2 LASTPROP $XRERR UNIQUE?
J 0
(-3775 1760);
DISPLAY 0.638298 (-3775 1760);
PAINT MONO (-3775 1760);
DISPLAY INVISIBLE (-3775 1760);
WIRE 3 682 (-7700 1150)(-7700 900);
WIRE 3 682 (-5700 900)(-7700 900);
WIRE 3 682 (-7700 1150)(-5700 1150);
WIRE 3 682 (-5700 1150)(-5700 900);
WIRE 16 682 (-7400 1650)(-7400 600);
WIRE 16 682 (-5875 1650)(-7400 1650);
WIRE 16 682 (-7400 600)(-5875 600);
WIRE 16 682 (-5875 600)(-5875 1650);
WIRE 3 682 (-6050 3450)(-6050 2925);
WIRE 3 682 (-5250 3450)(-6050 3450);
WIRE 3 682 (-6050 2925)(-5250 2925);
WIRE 3 682 (-5250 2925)(-5250 3450);
WIRE 16 -1 (-3500 1500)(-3500 1400);
WIRE 16 -1 (-3000 1500)(-3500 1500);
FORCEPROP 2 LAST SIG_NAME PD_FRU_WP
J 0
(-3460 1510);
DISPLAY 0.617021 (-3460 1510);
PAINT ORANGE (-3460 1510);
FORCEPROP 2 LASTPROP $XRERR UNIQUE?
J 0
(-3700 1510);
DISPLAY 0.638298 (-3700 1510);
PAINT MONO (-3700 1510);
DISPLAY INVISIBLE (-3700 1510);
WIRE 16 -1 (-4950 2850)(-4125 2850);
FORCEPROP 2 LAST SIG_NAME PU_TMP421_2_A0
J 2
(-4175 2860);
DISPLAY 0.617021 (-4175 2860);
PAINT ORANGE (-4175 2860);
FORCEPROP 2 LASTPROP $XRERR UNIQUE?
J 0
(-4415 2860);
DISPLAY 0.638298 (-4415 2860);
PAINT MONO (-4415 2860);
DISPLAY INVISIBLE (-4415 2860);
WIRE 16 -1 (-4775 4300)(-4300 4300);
WIRE 16 -1 (-4775 4175)(-4775 4300);
FORCEPROP 2 LAST SIG_NAME PD_TMP421_1_A0
J 0
(-4800 4310);
DISPLAY 0.617021 (-4800 4310);
PAINT ORANGE (-4800 4310);
FORCEPROP 2 LASTPROP $XRERR UNIQUE?
J 0
(-5040 4310);
DISPLAY 0.638298 (-5040 4310);
PAINT MONO (-5040 4310);
DISPLAY INVISIBLE (-5040 4310);
WIRE 16 -1 (-3525 3050)(-2725 3050);
FORCEPROP 2 LAST SIG_NAME SMB_SENSOR_TMP421_2_SDA
J 0
(-3435 3060);
DISPLAY 0.617021 (-3435 3060);
PAINT ORANGE (-3435 3060);
FORCEPROP 2 LASTPROP $XRERR UNIQUE?
J 0
(-3675 3060);
DISPLAY 0.638298 (-3675 3060);
PAINT MONO (-3675 3060);
DISPLAY INVISIBLE (-3675 3060);
WIRE 16 -1 (-2400 1550)(-1575 1550);
FORCEPROP 2 LAST SIG_NAME SMB_SENSOR_STBY_LVC3_SDA_R2
J 0
(-2310 1560);
DISPLAY 0.617021 (-2310 1560);
PAINT ORANGE (-2310 1560);
FORCEPROP 2 LASTPROP $XRERR UNIQUE?
J 0
(-2550 1560);
DISPLAY 0.638298 (-2550 1560);
PAINT MONO (-2550 1560);
DISPLAY INVISIBLE (-2550 1560);
WIRE 16 -1 (-4550 2900)(-4125 2900);
FORCEPROP 2 LAST SIG_NAME PD_TMP421_2_A1
J 2
(-4175 2910);
DISPLAY 0.617021 (-4175 2910);
PAINT ORANGE (-4175 2910);
FORCEPROP 2 LASTPROP $XRERR UNIQUE?
J 0
(-4415 2910);
DISPLAY 0.638298 (-4415 2910);
PAINT MONO (-4415 2910);
DISPLAY INVISIBLE (-4415 2910);
WIRE 16 -1 (-4675 3000)(-4875 3000);
WIRE 16 -1 (-4675 3075)(-4675 3000);
WIRE 16 -1 (-4125 3000)(-4675 3000);
FORCEPROP 2 LAST SIG_NAME ISENSE_TMP421_2_DXN
J 2
(-4175 3010);
DISPLAY 0.617021 (-4175 3010);
PAINT ORANGE (-4175 3010);
FORCEPROP 2 LASTPROP $XRERR UNIQUE?
J 0
(-4415 3010);
DISPLAY 0.638298 (-4415 3010);
PAINT MONO (-4415 3010);
DISPLAY INVISIBLE (-4415 3010);
WIRE 16 -1 (-4125 3050)(-4400 3050);
WIRE 16 -1 (-4675 3325)(-4900 3325);
FORCEPROP 2 LAST SIG_NAME ISENSE_TMP421_2_DXP
J 0
(-4835 3335);
DISPLAY 0.617021 (-4835 3335);
PAINT ORANGE (-4835 3335);
FORCEPROP 2 LASTPROP $XRERR UNIQUE?
J 0
(-5075 3335);
DISPLAY 0.638298 (-5075 3335);
PAINT MONO (-5075 3335);
DISPLAY INVISIBLE (-5075 3335);
WIRE 16 -1 (-4675 3325)(-4675 3275);
WIRE 16 -1 (-4400 3050)(-4400 3325);
WIRE 16 -1 (-4400 3325)(-4675 3325);
WIRE 16 -1 (-3900 1550)(-3000 1550);
FORCEPROP 2 LAST SIG_NAME SMB_SENSOR_STBY_LVC3_SCL_R2
J 0
(-3835 1560);
DISPLAY 0.617021 (-3835 1560);
PAINT ORANGE (-3835 1560);
FORCEPROP 2 LASTPROP $XRERR UNIQUE?
J 0
(-4075 1560);
DISPLAY 0.638298 (-4075 1560);
PAINT MONO (-4075 1560);
DISPLAY INVISIBLE (-4075 1560);
WIRE 16 -1 (-3700 4450)(-2750 4450);
FORCEPROP 2 LAST SIG_NAME SMB_SENSOR_TMP421_1_SCL
J 0
(-3610 4460);
DISPLAY 0.617021 (-3610 4460);
PAINT ORANGE (-3610 4460);
FORCEPROP 2 LASTPROP $XRERR UNIQUE?
J 0
(-3850 4460);
DISPLAY 0.638298 (-3850 4460);
PAINT MONO (-3850 4460);
DISPLAY INVISIBLE (-3850 4460);
WIRE 16 -1 (-3700 4500)(-3050 4500);
FORCEPROP 2 LAST SIG_NAME SMB_SENSOR_TMP421_1_SDA
J 0
(-3610 4510);
DISPLAY 0.617021 (-3610 4510);
PAINT ORANGE (-3610 4510);
FORCEPROP 2 LASTPROP $XRERR UNIQUE?
J 0
(-3850 4510);
DISPLAY 0.638298 (-3850 4510);
PAINT MONO (-3850 4510);
DISPLAY INVISIBLE (-3850 4510);
WIRE 16 -1 (-1375 1550)(-600 1550);
FORCEPROP 2 LAST SIG_NAME SMB_SENSOR_STBY_LVC3_SDA
J 0
(-1285 1560);
DISPLAY 0.617021 (-1285 1560);
PAINT ORANGE (-1285 1560);
WIRE 16 -1 (-4850 1550)(-4100 1550);
FORCEPROP 2 LAST SIG_NAME SMB_SENSOR_STBY_LVC3_SCL
J 0
(-4835 1560);
DISPLAY 0.617021 (-4835 1560);
PAINT ORANGE (-4835 1560);
WIRE 16 -1 (-2525 3050)(-2100 3050);
WIRE 16 -1 (-2100 3050)(-2100 4500);
WIRE 16 -1 (-2100 4500)(-1200 4500);
FORCEPROP 2 LAST SIG_NAME SMB_SENSOR_STBY_LVC3_SDA
J 0
(-1985 4510);
DISPLAY 0.617021 (-1985 4510);
PAINT ORANGE (-1985 4510);
WIRE 16 -1 (-2850 4500)(-2100 4500);
WIRE 16 -1 (-7650 1325)(-6825 1325);
FORCEPROP 2 LAST SIG_NAME SMB_SENSOR_BMC_STBY_LVC3_SCL
J 0
(-7635 1335);
DISPLAY 0.617021 (-7635 1335);
PAINT ORANGE (-7635 1335);
WIRE 16 -1 (-7650 1450)(-6825 1450);
FORCEPROP 2 LAST SIG_NAME SMB_SENSOR_BMC_STBY_LVC3_SDA
J 0
(-7635 1460);
DISPLAY 0.617021 (-7635 1460);
PAINT ORANGE (-7635 1460);
WIRE 16 -1 (-6425 1850)(-6425 1450);
WIRE 16 -1 (-6425 1450)(-5800 1450);
WIRE 16 -1 (-6625 1450)(-6425 1450);
FORCEPROP 2 LAST SIG_NAME SMB_SENSOR_STBY_LVC3_SDA
J 0
(-6535 1460);
DISPLAY 0.617021 (-6535 1460);
PAINT ORANGE (-6535 1460);
WIRE 16 -1 (-6075 1325)(-5800 1325);
WIRE 16 -1 (-6075 1850)(-6075 1325);
WIRE 16 -1 (-6625 1325)(-6075 1325);
FORCEPROP 2 LAST SIG_NAME SMB_SENSOR_STBY_LVC3_SCL
J 0
(-6560 1335);
DISPLAY 0.617021 (-6560 1335);
PAINT ORANGE (-6560 1335);
WIRE 16 -1 (-2550 4450)(-2050 4450);
WIRE 16 -1 (-2050 4450)(-1200 4450);
WIRE 16 -1 (-2050 3000)(-2050 4450);
FORCEPROP 2 LAST SIG_NAME SMB_SENSOR_STBY_LVC3_SCL
J 0
(-1985 4460);
DISPLAY 0.617021 (-1985 4460);
PAINT ORANGE (-1985 4460);
WIRE 16 -1 (-2200 3000)(-2050 3000);
WIRE 3 682 (-6000 4325)(-6000 4275);
WIRE 3 682 (-5950 4325)(-6000 4325);
WIRE 3 682 (-6000 4275)(-5950 4275);
WIRE 3 682 (-5950 4275)(-5950 4325);
WIRE 16 -1 (-5750 3050)(-5750 3000);
WIRE 16 -1 (-5125 3000)(-5750 3000);
FORCEPROP 2 LAST SIG_NAME ISENSE_TMP421_2_BC
J 0
(-5735 3010);
DISPLAY 0.617021 (-5735 3010);
PAINT ORANGE (-5735 3010);
FORCEPROP 2 LASTPROP $XRERR UNIQUE?
J 0
(-5975 3010);
DISPLAY 0.638298 (-5975 3010);
PAINT MONO (-5975 3010);
DISPLAY INVISIBLE (-5975 3010);
WIRE 16 -1 (-5075 3000)(-5125 3000);
WIRE 16 -1 (-5125 3150)(-5125 3000);
WIRE 16 -1 (-5600 3150)(-5125 3150);
WIRE 16 -1 (-5750 3325)(-5100 3325);
WIRE 16 -1 (-5750 3250)(-5750 3325);
FORCEPROP 2 LAST SIG_NAME ISENSE_TMP421_2_E
J 0
(-5910 3360);
DISPLAY 0.617021 (-5910 3360);
PAINT ORANGE (-5910 3360);
FORCEPROP 2 LASTPROP $XRERR UNIQUE?
J 0
(-6150 3360);
DISPLAY 0.638298 (-6150 3360);
PAINT MONO (-6150 3360);
DISPLAY INVISIBLE (-6150 3360);
WIRE 16 -1 (-3525 3000)(-2400 3000);
FORCEPROP 2 LAST SIG_NAME SMB_SENSOR_TMP421_2_SCL
J 0
(-3435 3010);
DISPLAY 0.617021 (-3435 3010);
PAINT ORANGE (-3435 3010);
FORCEPROP 2 LASTPROP $XRERR UNIQUE?
J 0
(-3675 3010);
DISPLAY 0.638298 (-3675 3010);
PAINT MONO (-3675 3010);
DISPLAY INVISIBLE (-3675 3010);
WIRE 16 -1 (-5050 4450)(-4850 4450);
WIRE 16 -1 (-4850 4525)(-4850 4450);
WIRE 16 -1 (-4300 4450)(-4850 4450);
FORCEPROP 2 LAST SIG_NAME ISENSE_TMP421_1_DXN
J 0
(-4835 4460);
DISPLAY 0.617021 (-4835 4460);
PAINT ORANGE (-4835 4460);
FORCEPROP 2 LASTPROP $XRERR UNIQUE?
J 0
(-5075 4460);
DISPLAY 0.638298 (-5075 4460);
PAINT MONO (-5075 4460);
DISPLAY INVISIBLE (-5075 4460);
WIRE 16 -1 (-4850 4775)(-5050 4775);
WIRE 16 -1 (-4850 4775)(-4850 4725);
WIRE 16 -1 (-4575 4775)(-4850 4775);
FORCEPROP 2 LAST SIG_NAME ISENSE_TMP421_1_DXP
J 0
(-4985 4785);
DISPLAY 0.617021 (-4985 4785);
PAINT ORANGE (-4985 4785);
FORCEPROP 2 LASTPROP $XRERR UNIQUE?
J 0
(-5225 4785);
DISPLAY 0.638298 (-5225 4785);
PAINT MONO (-5225 4785);
DISPLAY INVISIBLE (-5225 4785);
WIRE 16 -1 (-4300 4500)(-4575 4500);
WIRE 16 -1 (-4575 4500)(-4575 4775);
DOT 1 (-5325 4450);
DOT 1 (-5125 3000);
DOT 1 (-4675 3325);
DOT 1 (-3075 1650);
DOT 1 (-2050 4450);
DOT 1 (-2100 4500);
DOT 1 (-4850 4775);
DOT 1 (-4850 4450);
DOT 1 (-4675 3000);
DOT 1 (-6075 1325);
DOT 1 (-6400 2900);
DOT 1 (-6425 1450);
DOT 1 (-6400 4500);
FORCENOTE
TP FAB1 ADD BJT 0316
(-7300 4850) 0;
DISPLAY LEFT (-7300 4850);
DISPLAY 0.638298 (-7300 4850);
PAINT RED (-7300 4850);
FORCENOTE
TP FAB3-DVT DELETE BJT Q9W5 20161114
(-7300 4950) 0;
DISPLAY LEFT (-7300 4950);
DISPLAY 0.638298 (-7300 4950);
PAINT RED (-7300 4950);
FORCENOTE
TP FAB3 CHANGE SYMBOL 0902
(-7300 4900) 0;
DISPLAY LEFT (-7300 4900);
DISPLAY 0.638298 (-7300 4900);
PAINT RED (-7300 4900);
FORCENOTE
SMBUS ADDRESS 0X9E
(-6275 2475) 0;
DISPLAY LEFT (-6275 2475);
DISPLAY 1.021277 (-6275 2475);
PAINT PURPLE (-6275 2475);
FORCENOTE
ROOM=SM_THERM
(-8117 625) 0;
DISPLAY LEFT (-8117 625);
DISPLAY 0.617021 (-8117 625);
PAINT PURPLE (-8117 625);
FORCENOTE
TP FAB3 DEL RES 0902
(-6450 4900) 0;
DISPLAY LEFT (-6450 4900);
DISPLAY 0.638298 (-6450 4900);
PAINT RED (-6450 4900);
FORCENOTE
TP FAB3 CHANGE SYMBOL 0902
(-5950 4875) 0;
DISPLAY LEFT (-5950 4875);
DISPLAY 0.638298 (-5950 4875);
PAINT RED (-5950 4875);
FORCENOTE
TP FAB1 ADD RES 0316
(-6450 4850) 0;
DISPLAY LEFT (-6450 4850);
DISPLAY 0.638298 (-6450 4850);
PAINT RED (-6450 4850);
FORCENOTE
TP FAB1 DELETE RES (NO USE IE) 0118
(-7350 950) 0;
DISPLAY LEFT (-7350 950);
DISPLAY 1.021277 (-7350 950);
PAINT RED (-7350 950);
FORCENOTE
SMBUS ADDRESS 0XA8
(-2300 1175) 0;
DISPLAY LEFT (-2300 1175);
DISPLAY 1.021277 (-2300 1175);
PAINT PURPLE (-2300 1175);
FORCENOTE
TP FAB3 CHANGE SYMBOL 0902
(-6050 3475) 0;
DISPLAY LEFT (-6050 3475);
DISPLAY 0.638298 (-6050 3475);
PAINT RED (-6050 3475);
FORCENOTE
SMBUS ADDRESS 0X9C
(-6775 3925) 0;
DISPLAY LEFT (-6775 3925);
DISPLAY 1.021277 (-6775 3925);
PAINT PURPLE (-6775 3925);
FORCENOTE
TP FAB3 RECONNECTION 0902
(-6450 4950) 0;
DISPLAY LEFT (-6450 4950);
DISPLAY 0.638298 (-6450 4950);
PAINT RED (-6450 4950);
FORCENOTE
TP FAB1 CHANGE CONNECTION 0317
(-6125 4225) 0;
DISPLAY LEFT (-6125 4225);
DISPLAY 1.021277 (-6125 4225);
PAINT RED (-6125 4225);
QUIT
